G04 ================== begin FILE IDENTIFICATION RECORD ==================*
G04 Layout Name:  14545-sa.brd*
G04 Film Name:    TSMD*
G04 File Format:  Gerber RS274X*
G04 File Origin:  Cadence Allegro 16.5-S056*
G04 Origin Date:  Fri Aug 01 17:58:27 2014*
G04 *
G04 Layer:  VIA CLASS/PASTEMASK_TOP*
G04 Layer:  PIN/PASTEMASK_TOP*
G04 Layer:  PACKAGE GEOMETRY/PASTEMASK_TOP*
G04 Layer:  DRAWING FORMAT/LAYER_PCB_STORY*
G04 Layer:  DRAWING FORMAT/LAYER_PAST_T*
G04 Layer:  BOARD GEOMETRY/PANEL_OUTLINE*
G04 *
G04 Offset:    (0.00 0.00)*
G04 Mirror:    No*
G04 Mode:      Positive*
G04 Rotation:  0*
G04 FullContactRelief:  No*
G04 UndefLineWidth:     6.00*
G04 ================== end FILE IDENTIFICATION RECORD ====================*
%FSLAX35Y35*MOIN*%
%IR0*IPPOS*OFA0.00000B0.00000*MIA0B0*SFA1.00000B1.00000*%
%AMMACRO42*
4,1,40,.017,-.013,
.017,.013,
.016939,.013695,
.016759,.014368,
.016464,.015,
.016064,.015571,
.015571,.016064,
.015,.016464,
.014368,.016759,
.013695,.016939,
.013,.017,
-.013,.017,
-.013695,.016939,
-.014368,.016759,
-.015,.016464,
-.015571,.016064,
-.016064,.015571,
-.016464,.015,
-.016759,.014368,
-.016939,.013695,
-.017,.013,
-.017,-.013,
-.016939,-.013695,
-.016759,-.014368,
-.016464,-.015,
-.016064,-.015571,
-.015571,-.016064,
-.015,-.016464,
-.014368,-.016759,
-.013695,-.016939,
-.013,-.017,
.013,-.017,
.013695,-.016939,
.014368,-.016759,
.015,-.016464,
.015571,-.016064,
.016064,-.015571,
.016464,-.015,
.016759,-.014368,
.016939,-.013695,
.017,-.013,
0.0*
%
%ADD42MACRO42*%
%AMMACRO16*
4,1,40,.013,.017,
-.013,.017,
-.013695,.016939,
-.014368,.016759,
-.015,.016464,
-.015571,.016064,
-.016064,.015571,
-.016464,.015,
-.016759,.014368,
-.016939,.013695,
-.017,.013,
-.017,-.013,
-.016939,-.013695,
-.016759,-.014368,
-.016464,-.015,
-.016064,-.015571,
-.015571,-.016064,
-.015,-.016464,
-.014368,-.016759,
-.013695,-.016939,
-.013,-.017,
.013,-.017,
.013695,-.016939,
.014368,-.016759,
.015,-.016464,
.015571,-.016064,
.016064,-.015571,
.016464,-.015,
.016759,-.014368,
.016939,-.013695,
.017,-.013,
.017,.013,
.016939,.013695,
.016759,.014368,
.016464,.015,
.016064,.015571,
.015571,.016064,
.015,.016464,
.014368,.016759,
.013695,.016939,
.013,.017,
0.0*
%
%ADD16MACRO16*%
%AMMACRO50*
4,1,3,.025,.0125,
0.0,-.0125,
-.025,.0125,
.025,.0125,
0.0*
%
%ADD50MACRO50*%
%ADD76R,.23X.032*%
%ADD56R,.045X.11*%
%ADD17R,.11X.045*%
%AMMACRO66*
4,1,3,.0125,0.0,
-.0125,-.025,
-.0125,.025,
.0125,0.0,
0.0*
%
%ADD66MACRO66*%
%ADD12R,.142X.028*%
%ADD10R,.05X.05*%
%ADD11C,.086*%
%AMMACRO61*
4,1,40,-.007,-.0225,
-.008389,-.022378,
-.009736,-.022018,
-.011,-.021428,
-.012142,-.020628,
-.013128,-.019642,
-.013928,-.0185,
-.014518,-.017236,
-.014878,-.015889,
-.015,-.0145,
-.015,.0145,
-.014878,.015889,
-.014518,.017236,
-.013928,.0185,
-.013128,.019642,
-.012142,.020628,
-.011,.021428,
-.009736,.022018,
-.008389,.022378,
-.007,.0225,
.007,.0225,
.008389,.022378,
.009736,.022018,
.011,.021428,
.012142,.020628,
.013128,.019642,
.013928,.0185,
.014518,.017236,
.014878,.015889,
.015,.0145,
.015,-.0145,
.014878,-.015889,
.014518,-.017236,
.013928,-.0185,
.013128,-.019642,
.012142,-.020628,
.011,-.021428,
.009736,-.022018,
.008389,-.022378,
.007,-.0225,
-.007,-.0225,
0.0*
%
%ADD61MACRO61*%
%AMMACRO25*
4,1,40,.011,-.007,
.011,.007,
.010939,.007695,
.010759,.008368,
.010464,.009,
.010064,.009571,
.009571,.010064,
.009,.010464,
.008368,.010759,
.007695,.010939,
.007,.011,
-.007,.011,
-.007695,.010939,
-.008368,.010759,
-.009,.010464,
-.009571,.010064,
-.010064,.009571,
-.010464,.009,
-.010759,.008368,
-.010939,.007695,
-.011,.007,
-.011,-.007,
-.010939,-.007695,
-.010759,-.008368,
-.010464,-.009,
-.010064,-.009571,
-.009571,-.010064,
-.009,-.010464,
-.008368,-.010759,
-.007695,-.010939,
-.007,-.011,
.007,-.011,
.007695,-.010939,
.008368,-.010759,
.009,-.010464,
.009571,-.010064,
.010064,-.009571,
.010464,-.009,
.010759,-.008368,
.010939,-.007695,
.011,-.007,
0.0*
%
%ADD25MACRO25*%
%AMMACRO20*
4,1,40,.007,.011,
-.007,.011,
-.007695,.010939,
-.008368,.010759,
-.009,.010464,
-.009571,.010064,
-.010064,.009571,
-.010464,.009,
-.010759,.008368,
-.010939,.007695,
-.011,.007,
-.011,-.007,
-.010939,-.007695,
-.010759,-.008368,
-.010464,-.009,
-.010064,-.009571,
-.009571,-.010064,
-.009,-.010464,
-.008368,-.010759,
-.007695,-.010939,
-.007,-.011,
.007,-.011,
.007695,-.010939,
.008368,-.010759,
.009,-.010464,
.009571,-.010064,
.010064,-.009571,
.010464,-.009,
.010759,-.008368,
.010939,-.007695,
.011,-.007,
.011,.007,
.010939,.007695,
.010759,.008368,
.010464,.009,
.010064,.009571,
.009571,.010064,
.009,.010464,
.008368,.010759,
.007695,.010939,
.007,.011,
0.0*
%
%ADD20MACRO20*%
%AMMACRO40*
4,1,40,-.012,.008,
-.012,-.008,
-.011939,-.008695,
-.011759,-.009368,
-.011464,-.01,
-.011064,-.010571,
-.010571,-.011064,
-.01,-.011464,
-.009368,-.011759,
-.008695,-.011939,
-.008,-.012,
.008,-.012,
.008695,-.011939,
.009368,-.011759,
.01,-.011464,
.010571,-.011064,
.011064,-.010571,
.011464,-.01,
.011759,-.009368,
.011939,-.008695,
.012,-.008,
.012,.008,
.011939,.008695,
.011759,.009368,
.011464,.01,
.011064,.010571,
.010571,.011064,
.01,.011464,
.009368,.011759,
.008695,.011939,
.008,.012,
-.008,.012,
-.008695,.011939,
-.009368,.011759,
-.01,.011464,
-.010571,.011064,
-.011064,.010571,
-.011464,.01,
-.011759,.009368,
-.011939,.008695,
-.012,.008,
0.0*
%
%ADD40MACRO40*%
%AMMACRO54*
4,1,40,.008,.012,
-.008,.012,
-.008695,.011939,
-.009368,.011759,
-.01,.011464,
-.010571,.011064,
-.011064,.010571,
-.011464,.01,
-.011759,.009368,
-.011939,.008695,
-.012,.008,
-.012,-.008,
-.011939,-.008695,
-.011759,-.009368,
-.011464,-.01,
-.011064,-.010571,
-.010571,-.011064,
-.01,-.011464,
-.009368,-.011759,
-.008695,-.011939,
-.008,-.012,
.008,-.012,
.008695,-.011939,
.009368,-.011759,
.01,-.011464,
.010571,-.011064,
.011064,-.010571,
.011464,-.01,
.011759,-.009368,
.011939,-.008695,
.012,-.008,
.012,.008,
.011939,.008695,
.011759,.009368,
.011464,.01,
.011064,.010571,
.010571,.011064,
.01,.011464,
.009368,.011759,
.008695,.011939,
.008,.012,
0.0*
%
%ADD54MACRO54*%
%AMMACRO33*
4,1,40,-.013,-.017,
.013,-.017,
.013695,-.016939,
.014368,-.016759,
.015,-.016464,
.015571,-.016064,
.016064,-.015571,
.016464,-.015,
.016759,-.014368,
.016939,-.013695,
.017,-.013,
.017,.013,
.016939,.013695,
.016759,.014368,
.016464,.015,
.016064,.015571,
.015571,.016064,
.015,.016464,
.014368,.016759,
.013695,.016939,
.013,.017,
-.013,.017,
-.013695,.016939,
-.014368,.016759,
-.015,.016464,
-.015571,.016064,
-.016064,.015571,
-.016464,.015,
-.016759,.014368,
-.016939,.013695,
-.017,.013,
-.017,-.013,
-.016939,-.013695,
-.016759,-.014368,
-.016464,-.015,
-.016064,-.015571,
-.015571,-.016064,
-.015,-.016464,
-.014368,-.016759,
-.013695,-.016939,
-.013,-.017,
0.0*
%
%ADD33MACRO33*%
%AMMACRO43*
4,1,40,-.017,.013,
-.017,-.013,
-.016939,-.013695,
-.016759,-.014368,
-.016464,-.015,
-.016064,-.015571,
-.015571,-.016064,
-.015,-.016464,
-.014368,-.016759,
-.013695,-.016939,
-.013,-.017,
.013,-.017,
.013695,-.016939,
.014368,-.016759,
.015,-.016464,
.015571,-.016064,
.016064,-.015571,
.016464,-.015,
.016759,-.014368,
.016939,-.013695,
.017,-.013,
.017,.013,
.016939,.013695,
.016759,.014368,
.016464,.015,
.016064,.015571,
.015571,.016064,
.015,.016464,
.014368,.016759,
.013695,.016939,
.013,.017,
-.013,.017,
-.013695,.016939,
-.014368,.016759,
-.015,.016464,
-.015571,.016064,
-.016064,.015571,
-.016464,.015,
-.016759,.014368,
-.016939,.013695,
-.017,.013,
0.0*
%
%ADD43MACRO43*%
%AMMACRO26*
4,1,40,.011,-.007,
.011,.007,
.010939,.007695,
.010759,.008368,
.010464,.009,
.010064,.009571,
.009571,.010064,
.009,.010464,
.008368,.010759,
.007695,.010939,
.007,.011,
-.007,.011,
-.007695,.010939,
-.008368,.010759,
-.009,.010464,
-.009571,.010064,
-.010064,.009571,
-.010464,.009,
-.010759,.008368,
-.010939,.007695,
-.011,.007,
-.011,-.007,
-.010939,-.007695,
-.010759,-.008368,
-.010464,-.009,
-.010064,-.009571,
-.009571,-.010064,
-.009,-.010464,
-.008368,-.010759,
-.007695,-.010939,
-.007,-.011,
.007,-.011,
.007695,-.010939,
.008368,-.010759,
.009,-.010464,
.009571,-.010064,
.010064,-.009571,
.010464,-.009,
.010759,-.008368,
.010939,-.007695,
.011,-.007,
0.0*
%
%ADD26MACRO26*%
%AMMACRO21*
4,1,40,.007,.011,
-.007,.011,
-.007695,.010939,
-.008368,.010759,
-.009,.010464,
-.009571,.010064,
-.010064,.009571,
-.010464,.009,
-.010759,.008368,
-.010939,.007695,
-.011,.007,
-.011,-.007,
-.010939,-.007695,
-.010759,-.008368,
-.010464,-.009,
-.010064,-.009571,
-.009571,-.010064,
-.009,-.010464,
-.008368,-.010759,
-.007695,-.010939,
-.007,-.011,
.007,-.011,
.007695,-.010939,
.008368,-.010759,
.009,-.010464,
.009571,-.010064,
.010064,-.009571,
.010464,-.009,
.010759,-.008368,
.010939,-.007695,
.011,-.007,
.011,.007,
.010939,.007695,
.010759,.008368,
.010464,.009,
.010064,.009571,
.009571,.010064,
.009,.010464,
.008368,.010759,
.007695,.010939,
.007,.011,
0.0*
%
%ADD21MACRO21*%
%AMMACRO64*
4,1,20,.0635,-.1075,
.049,-.1075,
.049,-.118,
.0395,-.118,
.0395,-.1075,
-.0395,-.1075,
-.0395,-.118,
-.049,-.118,
-.049,-.1075,
-.0635,-.1075,
-.0635,.1075,
-.049,.1075,
-.049,.118,
-.0395,.118,
-.0395,.1075,
.0395,.1075,
.0395,.118,
.049,.118,
.049,.1075,
.0635,.1075,
.0635,-.1075,
0.0*
%
%ADD64MACRO64*%
%AMMACRO39*
4,1,40,-.012,.008,
-.012,-.008,
-.011939,-.008695,
-.011759,-.009368,
-.011464,-.01,
-.011064,-.010571,
-.010571,-.011064,
-.01,-.011464,
-.009368,-.011759,
-.008695,-.011939,
-.008,-.012,
.008,-.012,
.008695,-.011939,
.009368,-.011759,
.01,-.011464,
.010571,-.011064,
.011064,-.010571,
.011464,-.01,
.011759,-.009368,
.011939,-.008695,
.012,-.008,
.012,.008,
.011939,.008695,
.011759,.009368,
.011464,.01,
.011064,.010571,
.010571,.011064,
.01,.011464,
.009368,.011759,
.008695,.011939,
.008,.012,
-.008,.012,
-.008695,.011939,
-.009368,.011759,
-.01,.011464,
-.010571,.011064,
-.011064,.010571,
-.011464,.01,
-.011759,.009368,
-.011939,.008695,
-.012,.008,
0.0*
%
%ADD39MACRO39*%
%AMMACRO53*
4,1,40,.008,.012,
-.008,.012,
-.008695,.011939,
-.009368,.011759,
-.01,.011464,
-.010571,.011064,
-.011064,.010571,
-.011464,.01,
-.011759,.009368,
-.011939,.008695,
-.012,.008,
-.012,-.008,
-.011939,-.008695,
-.011759,-.009368,
-.011464,-.01,
-.011064,-.010571,
-.010571,-.011064,
-.01,-.011464,
-.009368,-.011759,
-.008695,-.011939,
-.008,-.012,
.008,-.012,
.008695,-.011939,
.009368,-.011759,
.01,-.011464,
.010571,-.011064,
.011064,-.010571,
.011464,-.01,
.011759,-.009368,
.011939,-.008695,
.012,-.008,
.012,.008,
.011939,.008695,
.011759,.009368,
.011464,.01,
.011064,.010571,
.010571,.011064,
.01,.011464,
.009368,.011759,
.008695,.011939,
.008,.012,
0.0*
%
%ADD53MACRO53*%
%AMMACRO34*
4,1,40,-.013,-.017,
.013,-.017,
.013695,-.016939,
.014368,-.016759,
.015,-.016464,
.015571,-.016064,
.016064,-.015571,
.016464,-.015,
.016759,-.014368,
.016939,-.013695,
.017,-.013,
.017,.013,
.016939,.013695,
.016759,.014368,
.016464,.015,
.016064,.015571,
.015571,.016064,
.015,.016464,
.014368,.016759,
.013695,.016939,
.013,.017,
-.013,.017,
-.013695,.016939,
-.014368,.016759,
-.015,.016464,
-.015571,.016064,
-.016064,.015571,
-.016464,.015,
-.016759,.014368,
-.016939,.013695,
-.017,.013,
-.017,-.013,
-.016939,-.013695,
-.016759,-.014368,
-.016464,-.015,
-.016064,-.015571,
-.015571,-.016064,
-.015,-.016464,
-.014368,-.016759,
-.013695,-.016939,
-.013,-.017,
0.0*
%
%ADD34MACRO34*%
%AMMACRO44*
4,1,40,-.017,.013,
-.017,-.013,
-.016939,-.013695,
-.016759,-.014368,
-.016464,-.015,
-.016064,-.015571,
-.015571,-.016064,
-.015,-.016464,
-.014368,-.016759,
-.013695,-.016939,
-.013,-.017,
.013,-.017,
.013695,-.016939,
.014368,-.016759,
.015,-.016464,
.015571,-.016064,
.016064,-.015571,
.016464,-.015,
.016759,-.014368,
.016939,-.013695,
.017,-.013,
.017,.013,
.016939,.013695,
.016759,.014368,
.016464,.015,
.016064,.015571,
.015571,.016064,
.015,.016464,
.014368,.016759,
.013695,.016939,
.013,.017,
-.013,.017,
-.013695,.016939,
-.014368,.016759,
-.015,.016464,
-.015571,.016064,
-.016064,.015571,
-.016464,.015,
-.016759,.014368,
-.016939,.013695,
-.017,.013,
0.0*
%
%ADD44MACRO44*%
%AMMACRO67*
4,1,3,.0125,-.025,
-.0125,0.0,
.0125,.025,
.0125,-.025,
0.0*
%
%ADD67MACRO67*%
%ADD30R,.04X.022*%
%ADD71R,.06X.012*%
%ADD70R,.022X.04*%
%AMMACRO49*
4,1,3,0.0,.0125,
.025,-.0125,
-.025,-.0125,
0.0,.0125,
0.0*
%
%ADD49MACRO49*%
%ADD74R,.023X.04*%
%ADD72R,.06X.014*%
%ADD65R,.044X.012*%
%ADD55R,.04X.016*%
%ADD60R,.014X.06*%
%ADD58R,.016X.04*%
%ADD47R,.012X.044*%
%ADD24R,.045X.03*%
%ADD48R,.133X.128*%
%ADD51R,.128X.133*%
%ADD18R,.075X.02*%
%ADD73R,.05X.065*%
%ADD19R,.036X.024*%
%ADD36R,.065X.05*%
%ADD35R,.065X.025*%
%ADD62R,.025X.065*%
%ADD59R,.048X.016*%
%ADD13R,.045X.055*%
%ADD57R,.016X.048*%
%ADD45R,.055X.045*%
%ADD63R,.054X.074*%
%ADD14R,.094X.026*%
%ADD29R,.09X.095*%
%AMMACRO69*
4,1,40,-.0225,.007,
-.022378,.008389,
-.022018,.009736,
-.021428,.011,
-.020628,.012142,
-.019642,.013128,
-.0185,.013928,
-.017236,.014518,
-.015889,.014878,
-.0145,.015,
.0145,.015,
.015889,.014878,
.017236,.014518,
.0185,.013928,
.019642,.013128,
.020628,.012142,
.021428,.011,
.022018,.009736,
.022378,.008389,
.0225,.007,
.0225,-.007,
.022378,-.008389,
.022018,-.009736,
.021428,-.011,
.020628,-.012142,
.019642,-.013128,
.0185,-.013928,
.017236,-.014518,
.015889,-.014878,
.0145,-.015,
-.0145,-.015,
-.015889,-.014878,
-.017236,-.014518,
-.0185,-.013928,
-.019642,-.013128,
-.020628,-.012142,
-.021428,-.011,
-.022018,-.009736,
-.022378,-.008389,
-.0225,-.007,
-.0225,.007,
0.0*
%
%ADD69MACRO69*%
%AMMACRO68*
4,1,40,.007,.0225,
.008389,.022378,
.009736,.022018,
.011,.021428,
.012142,.020628,
.013128,.019642,
.013928,.0185,
.014518,.017236,
.014878,.015889,
.015,.0145,
.015,-.0145,
.014878,-.015889,
.014518,-.017236,
.013928,-.0185,
.013128,-.019642,
.012142,-.020628,
.011,-.021428,
.009736,-.022018,
.008389,-.022378,
.007,-.0225,
-.007,-.0225,
-.008389,-.022378,
-.009736,-.022018,
-.011,-.021428,
-.012142,-.020628,
-.013128,-.019642,
-.013928,-.0185,
-.014518,-.017236,
-.014878,-.015889,
-.015,-.0145,
-.015,.0145,
-.014878,.015889,
-.014518,.017236,
-.013928,.0185,
-.013128,.019642,
-.012142,.020628,
-.011,.021428,
-.009736,.022018,
-.008389,.022378,
-.007,.0225,
.007,.0225,
0.0*
%
%ADD68MACRO68*%
%ADD52R,.095X.09*%
%ADD75R,.089X.059*%
%AMMACRO38*
4,1,40,-.008,-.012,
.008,-.012,
.008695,-.011939,
.009368,-.011759,
.01,-.011464,
.010571,-.011064,
.011064,-.010571,
.011464,-.01,
.011759,-.009368,
.011939,-.008695,
.012,-.008,
.012,.008,
.011939,.008695,
.011759,.009368,
.011464,.01,
.011064,.010571,
.010571,.011064,
.01,.011464,
.009368,.011759,
.008695,.011939,
.008,.012,
-.008,.012,
-.008695,.011939,
-.009368,.011759,
-.01,.011464,
-.010571,.011064,
-.011064,.010571,
-.011464,.01,
-.011759,.009368,
-.011939,.008695,
-.012,.008,
-.012,-.008,
-.011939,-.008695,
-.011759,-.009368,
-.011464,-.01,
-.011064,-.010571,
-.010571,-.011064,
-.01,-.011464,
-.009368,-.011759,
-.008695,-.011939,
-.008,-.012,
0.0*
%
%ADD38MACRO38*%
%AMMACRO32*
4,1,40,.012,-.008,
.012,.008,
.011939,.008695,
.011759,.009368,
.011464,.01,
.011064,.010571,
.010571,.011064,
.01,.011464,
.009368,.011759,
.008695,.011939,
.008,.012,
-.008,.012,
-.008695,.011939,
-.009368,.011759,
-.01,.011464,
-.010571,.011064,
-.011064,.010571,
-.011464,.01,
-.011759,.009368,
-.011939,.008695,
-.012,.008,
-.012,-.008,
-.011939,-.008695,
-.011759,-.009368,
-.011464,-.01,
-.011064,-.010571,
-.010571,-.011064,
-.01,-.011464,
-.009368,-.011759,
-.008695,-.011939,
-.008,-.012,
.008,-.012,
.008695,-.011939,
.009368,-.011759,
.01,-.011464,
.010571,-.011064,
.011064,-.010571,
.011464,-.01,
.011759,-.009368,
.011939,-.008695,
.012,-.008,
0.0*
%
%ADD32MACRO32*%
%AMMACRO22*
4,1,40,-.007,-.011,
.007,-.011,
.007695,-.010939,
.008368,-.010759,
.009,-.010464,
.009571,-.010064,
.010064,-.009571,
.010464,-.009,
.010759,-.008368,
.010939,-.007695,
.011,-.007,
.011,.007,
.010939,.007695,
.010759,.008368,
.010464,.009,
.010064,.009571,
.009571,.010064,
.009,.010464,
.008368,.010759,
.007695,.010939,
.007,.011,
-.007,.011,
-.007695,.010939,
-.008368,.010759,
-.009,.010464,
-.009571,.010064,
-.010064,.009571,
-.010464,.009,
-.010759,.008368,
-.010939,.007695,
-.011,.007,
-.011,-.007,
-.010939,-.007695,
-.010759,-.008368,
-.010464,-.009,
-.010064,-.009571,
-.009571,-.010064,
-.009,-.010464,
-.008368,-.010759,
-.007695,-.010939,
-.007,-.011,
0.0*
%
%ADD22MACRO22*%
%AMMACRO27*
4,1,40,-.011,.007,
-.011,-.007,
-.010939,-.007695,
-.010759,-.008368,
-.010464,-.009,
-.010064,-.009571,
-.009571,-.010064,
-.009,-.010464,
-.008368,-.010759,
-.007695,-.010939,
-.007,-.011,
.007,-.011,
.007695,-.010939,
.008368,-.010759,
.009,-.010464,
.009571,-.010064,
.010064,-.009571,
.010464,-.009,
.010759,-.008368,
.010939,-.007695,
.011,-.007,
.011,.007,
.010939,.007695,
.010759,.008368,
.010464,.009,
.010064,.009571,
.009571,.010064,
.009,.010464,
.008368,.010759,
.007695,.010939,
.007,.011,
-.007,.011,
-.007695,.010939,
-.008368,.010759,
-.009,.010464,
-.009571,.010064,
-.010064,.009571,
-.010464,.009,
-.010759,.008368,
-.010939,.007695,
-.011,.007,
0.0*
%
%ADD27MACRO27*%
%AMMACRO41*
4,1,40,.017,-.013,
.017,.013,
.016939,.013695,
.016759,.014368,
.016464,.015,
.016064,.015571,
.015571,.016064,
.015,.016464,
.014368,.016759,
.013695,.016939,
.013,.017,
-.013,.017,
-.013695,.016939,
-.014368,.016759,
-.015,.016464,
-.015571,.016064,
-.016064,.015571,
-.016464,.015,
-.016759,.014368,
-.016939,.013695,
-.017,.013,
-.017,-.013,
-.016939,-.013695,
-.016759,-.014368,
-.016464,-.015,
-.016064,-.015571,
-.015571,-.016064,
-.015,-.016464,
-.014368,-.016759,
-.013695,-.016939,
-.013,-.017,
.013,-.017,
.013695,-.016939,
.014368,-.016759,
.015,-.016464,
.015571,-.016064,
.016064,-.015571,
.016464,-.015,
.016759,-.014368,
.016939,-.013695,
.017,-.013,
0.0*
%
%ADD41MACRO41*%
%AMMACRO15*
4,1,40,.013,.017,
-.013,.017,
-.013695,.016939,
-.014368,.016759,
-.015,.016464,
-.015571,.016064,
-.016064,.015571,
-.016464,.015,
-.016759,.014368,
-.016939,.013695,
-.017,.013,
-.017,-.013,
-.016939,-.013695,
-.016759,-.014368,
-.016464,-.015,
-.016064,-.015571,
-.015571,-.016064,
-.015,-.016464,
-.014368,-.016759,
-.013695,-.016939,
-.013,-.017,
.013,-.017,
.013695,-.016939,
.014368,-.016759,
.015,-.016464,
.015571,-.016064,
.016064,-.015571,
.016464,-.015,
.016759,-.014368,
.016939,-.013695,
.017,-.013,
.017,.013,
.016939,.013695,
.016759,.014368,
.016464,.015,
.016064,.015571,
.015571,.016064,
.015,.016464,
.014368,.016759,
.013695,.016939,
.013,.017,
0.0*
%
%ADD15MACRO15*%
%AMMACRO46*
4,1,20,.1075,.0635,
.1075,.049,
.118,.049,
.118,.0395,
.1075,.0395,
.1075,-.0395,
.118,-.0395,
.118,-.049,
.1075,-.049,
.1075,-.0635,
-.1075,-.0635,
-.1075,-.049,
-.118,-.049,
-.118,-.0395,
-.1075,-.0395,
-.1075,.0395,
-.118,.0395,
-.118,.049,
-.1075,.049,
-.1075,.0635,
.1075,.0635,
0.0*
%
%ADD46MACRO46*%
%AMMACRO37*
4,1,40,-.008,-.012,
.008,-.012,
.008695,-.011939,
.009368,-.011759,
.01,-.011464,
.010571,-.011064,
.011064,-.010571,
.011464,-.01,
.011759,-.009368,
.011939,-.008695,
.012,-.008,
.012,.008,
.011939,.008695,
.011759,.009368,
.011464,.01,
.011064,.010571,
.010571,.011064,
.01,.011464,
.009368,.011759,
.008695,.011939,
.008,.012,
-.008,.012,
-.008695,.011939,
-.009368,.011759,
-.01,.011464,
-.010571,.011064,
-.011064,.010571,
-.011464,.01,
-.011759,.009368,
-.011939,.008695,
-.012,.008,
-.012,-.008,
-.011939,-.008695,
-.011759,-.009368,
-.011464,-.01,
-.011064,-.010571,
-.010571,-.011064,
-.01,-.011464,
-.009368,-.011759,
-.008695,-.011939,
-.008,-.012,
0.0*
%
%ADD37MACRO37*%
%AMMACRO31*
4,1,40,.012,-.008,
.012,.008,
.011939,.008695,
.011759,.009368,
.011464,.01,
.011064,.010571,
.010571,.011064,
.01,.011464,
.009368,.011759,
.008695,.011939,
.008,.012,
-.008,.012,
-.008695,.011939,
-.009368,.011759,
-.01,.011464,
-.010571,.011064,
-.011064,.010571,
-.011464,.01,
-.011759,.009368,
-.011939,.008695,
-.012,.008,
-.012,-.008,
-.011939,-.008695,
-.011759,-.009368,
-.011464,-.01,
-.011064,-.010571,
-.010571,-.011064,
-.01,-.011464,
-.009368,-.011759,
-.008695,-.011939,
-.008,-.012,
.008,-.012,
.008695,-.011939,
.009368,-.011759,
.01,-.011464,
.010571,-.011064,
.011064,-.010571,
.011464,-.01,
.011759,-.009368,
.011939,-.008695,
.012,-.008,
0.0*
%
%ADD31MACRO31*%
%AMMACRO23*
4,1,40,-.007,-.011,
.007,-.011,
.007695,-.010939,
.008368,-.010759,
.009,-.010464,
.009571,-.010064,
.010064,-.009571,
.010464,-.009,
.010759,-.008368,
.010939,-.007695,
.011,-.007,
.011,.007,
.010939,.007695,
.010759,.008368,
.010464,.009,
.010064,.009571,
.009571,.010064,
.009,.010464,
.008368,.010759,
.007695,.010939,
.007,.011,
-.007,.011,
-.007695,.010939,
-.008368,.010759,
-.009,.010464,
-.009571,.010064,
-.010064,.009571,
-.010464,.009,
-.010759,.008368,
-.010939,.007695,
-.011,.007,
-.011,-.007,
-.010939,-.007695,
-.010759,-.008368,
-.010464,-.009,
-.010064,-.009571,
-.009571,-.010064,
-.009,-.010464,
-.008368,-.010759,
-.007695,-.010939,
-.007,-.011,
0.0*
%
%ADD23MACRO23*%
%AMMACRO28*
4,1,40,-.011,.007,
-.011,-.007,
-.010939,-.007695,
-.010759,-.008368,
-.010464,-.009,
-.010064,-.009571,
-.009571,-.010064,
-.009,-.010464,
-.008368,-.010759,
-.007695,-.010939,
-.007,-.011,
.007,-.011,
.007695,-.010939,
.008368,-.010759,
.009,-.010464,
.009571,-.010064,
.010064,-.009571,
.010464,-.009,
.010759,-.008368,
.010939,-.007695,
.011,-.007,
.011,.007,
.010939,.007695,
.010759,.008368,
.010464,.009,
.010064,.009571,
.009571,.010064,
.009,.010464,
.008368,.010759,
.007695,.010939,
.007,.011,
-.007,.011,
-.007695,.010939,
-.008368,.010759,
-.009,.010464,
-.009571,.010064,
-.010064,.009571,
-.010464,.009,
-.010759,.008368,
-.010939,.007695,
-.011,.007,
0.0*
%
%ADD28MACRO28*%
%ADD77C,.02*%
%ADD78C,.006*%
G75*
%LPD*%
G75*
G36*
G01X1017308Y1473722D02*
Y1491397D01*
X991708D01*
Y1473722D01*
X1017308D01*
G37*
G36*
G01Y1453247D02*
Y1470922D01*
X991708D01*
Y1453247D01*
X1017308D01*
G37*
G36*
G01Y1433722D02*
Y1451397D01*
X991708D01*
Y1433722D01*
X1017308D01*
G37*
G36*
G01Y1553722D02*
Y1571397D01*
X991708D01*
Y1553722D01*
X1017308D01*
G37*
G36*
G01Y1533247D02*
Y1550922D01*
X991708D01*
Y1533247D01*
X1017308D01*
G37*
G36*
G01Y1513722D02*
Y1531397D01*
X991708D01*
Y1513722D01*
X1017308D01*
G37*
G36*
G01Y1493247D02*
Y1510922D01*
X991708D01*
Y1493247D01*
X1017308D01*
G37*
G36*
G01X991708Y1593722D02*
X1017307D01*
Y1610922D01*
X991708D01*
Y1593722D01*
G37*
G36*
G01X1017308Y1573247D02*
Y1590922D01*
X991708D01*
Y1573247D01*
X1017308D01*
G37*
G54D10*
X-30766Y56622D03*
X-33866Y1947322D03*
X21499Y17050D03*
X1010999Y18550D03*
X1008999Y1968550D03*
X1073334Y50022D03*
G54D20*
X55799Y203550D03*
X77799Y204550D03*
X55799Y207550D03*
X77799Y208550D03*
X55799Y211550D03*
X77801Y611450D03*
Y615450D03*
X31299Y611550D03*
X56299Y1017050D03*
X81300Y1008500D03*
X56236Y1021050D03*
Y1025050D03*
X73799Y1837550D03*
X82549Y1828613D03*
X74049Y1843113D03*
X82549Y1832613D03*
X73799Y1849050D03*
X18299Y1948050D03*
Y1952050D03*
Y1940050D03*
X52299Y1897050D03*
X148299Y517613D03*
X155999Y524850D03*
X163499D03*
X170999D03*
X143800Y545000D03*
X171299Y916113D03*
X105550Y972000D03*
X105499Y967850D03*
X124780Y1098482D03*
Y1094482D03*
X112799Y1298113D03*
X128300Y1361000D03*
X138700Y1335800D03*
X127799Y1342050D03*
X100549Y1476050D03*
X108049D03*
X114049Y1702613D03*
X170800Y1691200D03*
X230299Y105050D03*
X238299Y95550D03*
X230172Y92572D03*
X179472Y90572D03*
Y86572D03*
X183199Y152000D03*
X226298Y287114D03*
X240600Y269700D03*
X183199Y559300D03*
X226299Y693550D03*
X240000Y677100D03*
X183699Y963100D03*
X199199Y1367400D03*
X182699Y1773200D03*
X302299Y86613D03*
X316200Y105200D03*
X305299Y334050D03*
Y339050D03*
X329798Y337114D03*
Y333114D03*
X315000Y365200D03*
X312300Y779000D03*
X306799Y742050D03*
Y746050D03*
X331299Y745050D03*
Y741050D03*
X316000Y772200D03*
X303299Y1554550D03*
X327799Y1557550D03*
Y1553550D03*
X312800Y1591000D03*
X314800Y1587000D03*
X303299Y1558550D03*
X315000Y1582600D03*
X310521Y1944909D03*
Y1948909D03*
X336021Y1947409D03*
Y1943409D03*
X318200Y1971900D03*
X370800Y46500D03*
X375400Y42300D03*
X751278Y323924D03*
Y328924D03*
X749996Y724882D03*
Y729882D03*
X750633Y1126392D03*
Y1131392D03*
X753627Y1531296D03*
Y1536296D03*
X697349Y1801634D03*
Y1808634D03*
X750114Y1937713D03*
Y1942213D03*
X813299Y167050D03*
X820799D03*
X828299D03*
X797299Y336050D03*
Y332050D03*
X776299Y326550D03*
Y322550D03*
X774299Y724050D03*
Y728550D03*
X795799Y736050D03*
Y732050D03*
Y1133050D03*
Y1137050D03*
X775299Y1127550D03*
Y1123550D03*
X798481Y1538893D03*
Y1542893D03*
X777481Y1527893D03*
Y1531893D03*
X813799Y1788050D03*
X821299D03*
X828799D03*
X796981Y1944393D03*
Y1948393D03*
X774799Y1935050D03*
Y1939050D03*
X902299Y103050D03*
Y107050D03*
X845800Y276800D03*
X912699Y557800D03*
X844500Y677700D03*
X913199Y962100D03*
X844100Y1083200D03*
X869799Y1359550D03*
Y1367550D03*
Y1363550D03*
X846100Y1488100D03*
X912699Y1771700D03*
X846599Y1893850D03*
X927699Y158500D03*
G54D11*
X-39052Y28742D03*
X-43327Y310478D03*
X-39686Y917251D03*
X-38801Y1082342D03*
X-44886Y1294251D03*
X-43103Y1928864D03*
X1071932Y32074D03*
X1074813Y1348051D03*
X1076613Y1740651D03*
X1074813Y1957551D03*
G54D30*
X95000Y1113000D03*
X86000D03*
X176500Y414500D03*
X133000Y1196000D03*
X142000D03*
X185500Y414500D03*
X203500Y812500D03*
X212500D03*
X201000Y1655500D03*
X210000D03*
X326000Y380000D03*
X317000D03*
X319500Y785500D03*
X310500D03*
X319500Y1597000D03*
X310500D03*
X369000Y53000D03*
X360000D03*
X753000Y362500D03*
X756000Y761500D03*
X752900Y1164800D03*
X755500Y1568000D03*
X756000Y1972000D03*
X762000Y362500D03*
X765000Y761500D03*
X761900Y1164800D03*
X764500Y1568000D03*
X765000Y1972000D03*
X877500Y1721500D03*
X883500D03*
G54D21*
X59199Y203550D03*
X81199Y204550D03*
X59199Y207550D03*
X81199Y208550D03*
X59199Y211550D03*
X81201Y611450D03*
Y615450D03*
X34699Y611550D03*
X59699Y1017050D03*
X84700Y1008500D03*
X59636Y1021050D03*
Y1025050D03*
X77199Y1837550D03*
X85949Y1828613D03*
X77449Y1843113D03*
X85949Y1832613D03*
X77199Y1849050D03*
X21699Y1948050D03*
Y1952050D03*
Y1940050D03*
X55699Y1897050D03*
X151699Y517613D03*
X159399Y524850D03*
X166899D03*
X174399D03*
X147200Y545000D03*
X174699Y916113D03*
X108950Y972000D03*
X108899Y967850D03*
X128180Y1098482D03*
Y1094482D03*
X116199Y1298113D03*
X131700Y1361000D03*
X142100Y1335800D03*
X131199Y1342050D03*
X103949Y1476050D03*
X111449D03*
X117449Y1702613D03*
X174200Y1691200D03*
X233699Y105050D03*
X241699Y95550D03*
X233572Y92572D03*
X182872Y90572D03*
Y86572D03*
X186599Y152000D03*
X229698Y287114D03*
X244000Y269700D03*
X186599Y559300D03*
X229699Y693550D03*
X243400Y677100D03*
X187099Y963100D03*
X202599Y1367400D03*
X186099Y1773200D03*
X305699Y86613D03*
X319600Y105200D03*
X308699Y334050D03*
Y339050D03*
X333198Y337114D03*
Y333114D03*
X318400Y365200D03*
X315700Y779000D03*
X310199Y742050D03*
Y746050D03*
X334699Y745050D03*
Y741050D03*
X319400Y772200D03*
X306699Y1554550D03*
X331199Y1557550D03*
Y1553550D03*
X316200Y1591000D03*
X318200Y1587000D03*
X306699Y1558550D03*
X318400Y1582600D03*
X313921Y1944909D03*
Y1948909D03*
X339421Y1947409D03*
Y1943409D03*
X321600Y1971900D03*
X374200Y46500D03*
X378800Y42300D03*
X754678Y323924D03*
Y328924D03*
X753396Y724882D03*
Y729882D03*
X754033Y1126392D03*
Y1131392D03*
X757027Y1531296D03*
Y1536296D03*
X700749Y1801634D03*
Y1808634D03*
X753514Y1937713D03*
Y1942213D03*
X816699Y167050D03*
X824199D03*
X831699D03*
X800699Y336050D03*
Y332050D03*
X779699Y326550D03*
Y322550D03*
X777699Y724050D03*
Y728550D03*
X799199Y736050D03*
Y732050D03*
Y1133050D03*
Y1137050D03*
X778699Y1127550D03*
Y1123550D03*
X801881Y1538893D03*
Y1542893D03*
X780881Y1527893D03*
Y1531893D03*
X817199Y1788050D03*
X824699D03*
X832199D03*
X800381Y1944393D03*
Y1948393D03*
X778199Y1935050D03*
Y1939050D03*
X905699Y103050D03*
Y107050D03*
X849200Y276800D03*
X916099Y557800D03*
X847900Y677700D03*
X916599Y962100D03*
X847500Y1083200D03*
X873199Y1359550D03*
Y1367550D03*
Y1363550D03*
X849500Y1488100D03*
X916099Y1771700D03*
X849999Y1893850D03*
X931099Y158500D03*
G54D12*
X12560Y231121D03*
Y227184D03*
Y223247D03*
Y211435D03*
Y207498D03*
Y203561D03*
Y199624D03*
Y195687D03*
Y191750D03*
Y187813D03*
Y183876D03*
Y179939D03*
Y176002D03*
Y172065D03*
Y246869D03*
Y242932D03*
Y238995D03*
Y235058D03*
X12569Y372041D03*
Y375978D03*
Y379915D03*
Y383852D03*
Y387789D03*
Y391726D03*
Y395663D03*
Y399600D03*
Y403537D03*
Y407474D03*
Y411411D03*
Y431098D03*
Y427161D03*
Y423223D03*
Y435035D03*
Y438972D03*
Y442909D03*
Y446846D03*
Y450783D03*
Y454720D03*
Y458657D03*
Y462594D03*
Y466531D03*
Y470468D03*
Y474405D03*
Y478342D03*
Y482279D03*
Y486216D03*
Y490153D03*
Y494090D03*
Y498027D03*
Y501964D03*
Y505901D03*
Y509838D03*
Y513775D03*
Y517712D03*
Y521649D03*
Y525586D03*
Y529523D03*
Y533460D03*
Y537397D03*
Y541334D03*
Y545271D03*
Y549208D03*
Y553145D03*
Y557082D03*
Y561019D03*
Y564956D03*
Y568893D03*
Y572830D03*
Y576767D03*
Y580704D03*
Y584641D03*
Y588578D03*
Y592515D03*
Y596452D03*
Y600389D03*
Y604326D03*
Y608263D03*
Y612200D03*
Y616137D03*
Y620074D03*
Y624011D03*
Y627948D03*
Y631885D03*
Y635822D03*
Y639759D03*
Y643696D03*
Y647633D03*
Y651570D03*
Y655507D03*
Y659444D03*
Y671255D03*
Y667318D03*
Y663381D03*
Y675192D03*
Y679129D03*
Y683066D03*
Y690940D03*
Y687003D03*
Y694877D03*
Y698814D03*
X12560Y813010D03*
Y809073D03*
Y805136D03*
Y801199D03*
Y797262D03*
Y793325D03*
Y789388D03*
Y785451D03*
Y781514D03*
Y856318D03*
Y852381D03*
Y848444D03*
Y844507D03*
Y840570D03*
Y836633D03*
Y832696D03*
Y820884D03*
Y816947D03*
Y1223247D03*
Y1219310D03*
Y1215373D03*
Y1211436D03*
Y1207499D03*
Y1195687D03*
Y1191750D03*
Y1187813D03*
Y1183876D03*
Y1179939D03*
Y1176002D03*
Y1172065D03*
Y1168128D03*
Y1164191D03*
Y1160254D03*
Y1156317D03*
Y1231121D03*
Y1227184D03*
X12569Y1356293D03*
Y1360230D03*
Y1364167D03*
Y1368104D03*
Y1372041D03*
Y1375978D03*
Y1379915D03*
Y1383852D03*
Y1387789D03*
Y1391726D03*
Y1395663D03*
Y1415350D03*
Y1411413D03*
Y1407475D03*
Y1419287D03*
Y1423224D03*
Y1427161D03*
Y1431098D03*
Y1435035D03*
Y1438972D03*
Y1442909D03*
Y1446846D03*
Y1450783D03*
Y1454720D03*
Y1458657D03*
Y1462594D03*
Y1466531D03*
Y1470468D03*
Y1474405D03*
Y1478342D03*
Y1482279D03*
Y1486216D03*
Y1490153D03*
Y1494090D03*
Y1498027D03*
Y1501964D03*
Y1505901D03*
Y1509838D03*
Y1513775D03*
Y1517712D03*
Y1521649D03*
Y1525586D03*
Y1529523D03*
Y1533460D03*
Y1537397D03*
Y1541334D03*
Y1545271D03*
Y1549208D03*
Y1553145D03*
Y1557082D03*
Y1561019D03*
Y1564956D03*
Y1568893D03*
Y1572830D03*
Y1576767D03*
Y1580704D03*
Y1584641D03*
Y1588578D03*
Y1592515D03*
Y1596452D03*
Y1600389D03*
Y1604326D03*
Y1608263D03*
Y1612200D03*
Y1616137D03*
Y1620074D03*
Y1624011D03*
Y1627948D03*
Y1631885D03*
Y1635822D03*
Y1639759D03*
Y1643696D03*
Y1655507D03*
Y1651570D03*
Y1647633D03*
Y1659444D03*
Y1663381D03*
Y1667318D03*
Y1675192D03*
Y1671255D03*
Y1679129D03*
Y1683066D03*
X12560Y1805136D03*
Y1801199D03*
Y1797262D03*
Y1793325D03*
Y1789388D03*
Y1785451D03*
Y1781514D03*
Y1777577D03*
Y1773640D03*
Y1769703D03*
Y1765766D03*
Y1840570D03*
Y1836633D03*
Y1832696D03*
Y1828759D03*
Y1824822D03*
Y1820885D03*
Y1816948D03*
G54D31*
X88300Y1097500D03*
Y1104500D03*
X57299Y1901550D03*
X39799Y1921550D03*
X131799Y224550D03*
Y228050D03*
Y249050D03*
Y252550D03*
X135238Y630065D03*
Y633565D03*
Y654565D03*
Y658065D03*
X132799Y1035550D03*
Y1039050D03*
Y1060050D03*
Y1063550D03*
X143300Y1206000D03*
X109250Y1348100D03*
Y1344600D03*
X131190Y1441241D03*
Y1444741D03*
Y1465741D03*
Y1469241D03*
X131892Y1846254D03*
Y1849754D03*
Y1870754D03*
Y1874254D03*
X859278Y224924D03*
Y228424D03*
Y249424D03*
Y252924D03*
X859496Y630382D03*
Y633882D03*
Y654882D03*
Y658382D03*
X859133Y1035892D03*
Y1039392D03*
Y1060892D03*
Y1064392D03*
X860627Y1440796D03*
Y1444296D03*
Y1465796D03*
Y1469296D03*
X862614Y1846613D03*
Y1850113D03*
Y1871113D03*
Y1874613D03*
G54D22*
X51799Y217100D03*
X48400Y635500D03*
X34699Y616050D03*
X48400Y639600D03*
X79199Y642550D03*
X38800Y607326D03*
Y603200D03*
X35500Y597400D03*
Y593300D03*
X43100Y597400D03*
X60449Y656487D03*
Y652487D03*
Y648487D03*
X82700Y1013000D03*
X87299Y1000450D03*
Y1004450D03*
X92700Y1557500D03*
Y1553500D03*
X41699Y1838050D03*
Y1842050D03*
X67299Y1851900D03*
X21699Y1944050D03*
Y1936050D03*
X158199Y165050D03*
Y161050D03*
X170300Y420300D03*
X137699Y423113D03*
Y427113D03*
X170300Y424300D03*
X157499Y540050D03*
Y544250D03*
X157699Y570050D03*
Y566050D03*
X158199Y975550D03*
Y971550D03*
X174700Y922700D03*
X122199Y1125050D03*
X101299Y1081700D03*
Y1077400D03*
X143200Y1202000D03*
X139700Y1210000D03*
X134700Y1202000D03*
Y1206000D03*
X123199Y1356050D03*
Y1352050D03*
X131700Y1365000D03*
X123699Y1343050D03*
X128000Y1319900D03*
X118949Y1476050D03*
X147699Y1722550D03*
Y1718550D03*
X109199Y1716613D03*
Y1720613D03*
X158171Y1786909D03*
Y1782909D03*
X233699Y101050D03*
X182826Y82428D03*
X233699Y97050D03*
X180199Y165050D03*
Y161050D03*
Y156550D03*
X232100Y283000D03*
X179700Y420500D03*
X180199Y564050D03*
Y572050D03*
Y568050D03*
X229700Y689500D03*
X198800Y823000D03*
X179949Y976550D03*
Y972550D03*
X180199Y967550D03*
X183800Y931600D03*
X227950Y1082500D03*
X194699Y1381050D03*
Y1377050D03*
Y1373050D03*
X228200Y1480100D03*
X233100Y1499300D03*
X198749Y1630613D03*
X206700Y1649500D03*
X202200Y1645500D03*
X180764Y1786613D03*
Y1782613D03*
Y1778613D03*
X337699Y63050D03*
Y67050D03*
X305700Y90700D03*
X310199Y360050D03*
Y356050D03*
X308699Y343550D03*
X311199Y767050D03*
Y762550D03*
X310199Y750050D03*
Y1573050D03*
X306699Y1562550D03*
X313477Y1966191D03*
Y1962191D03*
X313558Y1953328D03*
X404199Y56050D03*
X386699Y30550D03*
Y26050D03*
X404199Y51050D03*
X378699Y53050D03*
Y57050D03*
X651749Y1803634D03*
Y1796134D03*
X651249Y1818634D03*
X757200Y351500D03*
X755200Y1154500D03*
X739749Y1798634D03*
Y1814134D03*
Y1806634D03*
X697249Y1821634D03*
Y1825634D03*
X757200Y1961000D03*
X760700Y355500D03*
X761700Y755000D03*
X758200Y751000D03*
X758700Y1158500D03*
Y1556500D03*
X762200Y1561000D03*
X789249Y1804634D03*
Y1800634D03*
X817199Y1825550D03*
Y1821550D03*
X777749Y1817634D03*
X760700Y1965000D03*
X905699Y99050D03*
X874928Y163924D03*
Y159924D03*
X849178Y280924D03*
X908646Y562882D03*
Y570882D03*
X886699Y570550D03*
X908646Y566882D03*
X886699Y565050D03*
X847896Y681882D03*
X908533Y974392D03*
X886533Y975892D03*
X908533Y970392D03*
X886533Y971892D03*
X908533Y966392D03*
X847533Y1087392D03*
X873527Y1379796D03*
Y1375796D03*
X861799Y1372200D03*
X849527Y1492296D03*
X908264Y1785613D03*
X886300Y1786300D03*
X908264Y1781613D03*
X886264Y1782213D03*
X908264Y1777613D03*
X881301Y1727450D03*
X888801D03*
X850014Y1898113D03*
X925928Y168424D03*
Y164424D03*
X925699Y172550D03*
G54D13*
X13700Y1117000D03*
Y1109000D03*
X27300Y134000D03*
X19700D03*
X27300Y126000D03*
X19700D03*
X51700Y739000D03*
X59300D03*
X21300Y1117000D03*
Y1109000D03*
X104099Y1597150D03*
X111699D03*
X232199Y33550D03*
X239799D03*
X232199Y51550D03*
X239799D03*
X232199Y42550D03*
X239799D03*
X232199Y60550D03*
X239799D03*
X232199Y69550D03*
X239799D03*
X951199Y46050D03*
X958799D03*
X951199Y64050D03*
X958799D03*
X951199Y55050D03*
X958799D03*
X949199Y101550D03*
X956799D03*
X951199Y73050D03*
X958799D03*
X951199Y82050D03*
X958799D03*
G54D40*
X21799Y1956050D03*
X39799Y1918050D03*
X104299Y145050D03*
Y141550D03*
X108799Y129550D03*
Y126050D03*
X104245Y550988D03*
Y547488D03*
X104745Y525988D03*
Y522488D03*
X106345Y956489D03*
Y952989D03*
X103345Y931489D03*
Y927989D03*
X122800Y1113500D03*
X132750Y1081100D03*
Y1077600D03*
X107628Y1361952D03*
Y1358452D03*
X104128Y1336952D03*
Y1333452D03*
X107299Y1767550D03*
Y1764050D03*
X105299Y1743050D03*
Y1739550D03*
X183299Y99050D03*
X181999Y524850D03*
X701349Y1813134D03*
X839299Y167550D03*
X839799Y1788050D03*
X907299Y124550D03*
X954799Y96050D03*
G54D23*
X48399Y217100D03*
X45000Y635500D03*
X31299Y616050D03*
X45000Y639600D03*
X75799Y642550D03*
X35400Y607326D03*
Y603200D03*
X32100Y597400D03*
Y593300D03*
X39700Y597400D03*
X57049Y656487D03*
Y652487D03*
Y648487D03*
X79300Y1013000D03*
X83899Y1000450D03*
Y1004450D03*
X89300Y1557500D03*
Y1553500D03*
X38299Y1838050D03*
Y1842050D03*
X63899Y1851900D03*
X18299Y1944050D03*
Y1936050D03*
X176799Y165050D03*
X154799D03*
X176799Y161050D03*
X154799D03*
X176799Y156550D03*
X176300Y420500D03*
X166900Y420300D03*
X134299Y423113D03*
Y427113D03*
X166900Y424300D03*
X176799Y564050D03*
X154099Y540050D03*
Y544250D03*
X176799Y572050D03*
X154299Y570050D03*
X176799Y568050D03*
X154299Y566050D03*
X176549Y976550D03*
X154799Y975550D03*
X176549Y972550D03*
X154799Y971550D03*
X176799Y967550D03*
X171300Y922700D03*
X118799Y1125050D03*
X97899Y1081700D03*
Y1077400D03*
X139800Y1202000D03*
X136300Y1210000D03*
X131300Y1202000D03*
Y1206000D03*
X119799Y1356050D03*
Y1352050D03*
X128300Y1365000D03*
X120299Y1343050D03*
X124600Y1319900D03*
X115549Y1476050D03*
X144299Y1722550D03*
Y1718550D03*
X105799Y1716613D03*
Y1720613D03*
X177364Y1786613D03*
X154771Y1786909D03*
X177364Y1782613D03*
X154771Y1782909D03*
X177364Y1778613D03*
X230299Y101050D03*
X179426Y82428D03*
X230299Y97050D03*
X228700Y283000D03*
X226300Y689500D03*
X195400Y823000D03*
X180400Y931600D03*
X224550Y1082500D03*
X191299Y1381050D03*
Y1377050D03*
Y1373050D03*
X224800Y1480100D03*
X229700Y1499300D03*
X195349Y1630613D03*
X203300Y1649500D03*
X198800Y1645500D03*
X334299Y63050D03*
Y67050D03*
X302300Y90700D03*
X306799Y360050D03*
Y356050D03*
X305299Y343550D03*
X307799Y767050D03*
Y762550D03*
X306799Y750050D03*
Y1573050D03*
X303299Y1562550D03*
X310077Y1966191D03*
Y1962191D03*
X310158Y1953328D03*
X400799Y56050D03*
X383299Y30550D03*
Y26050D03*
X400799Y51050D03*
X375299Y53050D03*
Y57050D03*
X648349Y1803634D03*
Y1796134D03*
X647849Y1818634D03*
X757300Y355500D03*
X753800Y351500D03*
X754800Y751000D03*
X755300Y1158500D03*
X751800Y1154500D03*
X755300Y1556500D03*
X736349Y1798634D03*
Y1814134D03*
Y1806634D03*
X693849Y1821634D03*
Y1825634D03*
X757300Y1965000D03*
X753800Y1961000D03*
X758300Y755000D03*
X758800Y1561000D03*
X785849Y1804634D03*
Y1800634D03*
X813799Y1825550D03*
Y1821550D03*
X774349Y1817634D03*
X902299Y99050D03*
X871528Y163924D03*
X922528Y168424D03*
X871528Y159924D03*
X922528Y164424D03*
X922299Y172550D03*
X845778Y280924D03*
X905246Y562882D03*
Y570882D03*
X883299Y570550D03*
X905246Y566882D03*
X883299Y565050D03*
X844496Y681882D03*
X905133Y974392D03*
X883133Y975892D03*
X905133Y970392D03*
X883133Y971892D03*
X905133Y966392D03*
X844133Y1087392D03*
X870127Y1379796D03*
Y1375796D03*
X858399Y1372200D03*
X846127Y1492296D03*
X904864Y1785613D03*
X882900Y1786300D03*
X904864Y1781613D03*
X882864Y1782213D03*
X904864Y1777613D03*
X877901Y1727450D03*
X885401D03*
X846614Y1898113D03*
G54D41*
X49999Y1971850D03*
X143499Y523413D03*
X166499Y921913D03*
X136600Y1180200D03*
X107999Y1303913D03*
X109499Y1708413D03*
X218998Y317914D03*
X213598Y350914D03*
X218499Y724850D03*
X214599Y757850D03*
X217600Y1127800D03*
X217999Y1534850D03*
X218814Y1925913D03*
X213600Y1962400D03*
X297499Y92413D03*
X783049Y1819434D03*
X788049D03*
X858999Y311850D03*
X864900Y344900D03*
X855696Y712182D03*
X862896Y746382D03*
X855333Y1117692D03*
X862933Y1149192D03*
X857827Y1522596D03*
X865700Y1552400D03*
X857314Y1928413D03*
X864500Y1962200D03*
G54D32*
X84700Y1097500D03*
Y1104500D03*
X53699Y1901550D03*
X36199Y1921550D03*
X128199Y224550D03*
Y228050D03*
Y249050D03*
Y252550D03*
X131638Y630065D03*
Y633565D03*
Y654565D03*
Y658065D03*
X129199Y1035550D03*
Y1039050D03*
Y1060050D03*
Y1063550D03*
X139700Y1206000D03*
X105650Y1348100D03*
Y1344600D03*
X127590Y1441241D03*
Y1444741D03*
Y1465741D03*
Y1469241D03*
X128292Y1846254D03*
Y1849754D03*
Y1870754D03*
Y1874254D03*
X855678Y224924D03*
Y228424D03*
Y249424D03*
Y252924D03*
X855896Y630382D03*
Y633882D03*
Y654882D03*
Y658382D03*
X855533Y1035892D03*
Y1039392D03*
Y1060892D03*
Y1064392D03*
X857027Y1440796D03*
Y1444296D03*
Y1465796D03*
Y1469296D03*
X859014Y1846613D03*
Y1850113D03*
Y1871113D03*
Y1874613D03*
G54D14*
X85630Y41141D03*
Y46141D03*
Y51141D03*
Y56141D03*
Y61141D03*
Y66141D03*
Y136141D03*
Y141141D03*
Y146141D03*
Y71141D03*
Y76141D03*
Y81141D03*
Y86141D03*
Y91141D03*
Y96141D03*
Y101141D03*
Y106141D03*
Y111141D03*
Y151141D03*
Y156141D03*
Y161141D03*
Y166141D03*
Y446653D03*
Y451653D03*
Y456653D03*
Y461653D03*
Y466653D03*
Y471653D03*
Y476653D03*
Y481653D03*
Y541653D03*
Y546653D03*
Y551653D03*
Y556653D03*
Y561653D03*
Y486653D03*
Y491653D03*
Y496653D03*
Y501653D03*
Y506653D03*
Y511653D03*
Y516653D03*
Y566653D03*
Y571653D03*
Y852165D03*
Y857165D03*
Y862165D03*
Y867165D03*
Y872165D03*
Y877165D03*
Y882165D03*
Y887165D03*
Y892165D03*
Y947165D03*
Y952165D03*
Y957165D03*
Y962165D03*
Y967165D03*
Y972165D03*
Y977165D03*
Y897165D03*
Y902165D03*
Y907165D03*
Y912165D03*
Y917165D03*
Y922165D03*
Y1257677D03*
Y1262677D03*
Y1267677D03*
Y1272677D03*
Y1277677D03*
Y1282677D03*
Y1287677D03*
Y1292677D03*
Y1297677D03*
Y1302677D03*
Y1307677D03*
Y1352677D03*
Y1357677D03*
Y1362677D03*
Y1367677D03*
Y1372677D03*
Y1377677D03*
Y1382677D03*
Y1312677D03*
Y1317677D03*
Y1322677D03*
Y1327677D03*
Y1663189D03*
Y1668189D03*
Y1673189D03*
Y1678189D03*
Y1683189D03*
Y1688189D03*
Y1693189D03*
Y1698189D03*
Y1703189D03*
Y1708189D03*
Y1713189D03*
Y1718189D03*
Y1723189D03*
Y1758189D03*
Y1763189D03*
Y1768189D03*
Y1773189D03*
Y1778189D03*
Y1783189D03*
Y1788189D03*
Y1728189D03*
Y1733189D03*
X150591Y228937D03*
Y223937D03*
Y218937D03*
Y213937D03*
Y208937D03*
Y203937D03*
Y233937D03*
Y313937D03*
Y308937D03*
Y303937D03*
Y298937D03*
Y293937D03*
Y288937D03*
Y283937D03*
Y278937D03*
Y273937D03*
Y268937D03*
Y263937D03*
Y258937D03*
Y328937D03*
Y323937D03*
Y318937D03*
Y639449D03*
Y634449D03*
Y629449D03*
Y624449D03*
Y619449D03*
Y614449D03*
Y609449D03*
Y729449D03*
Y724449D03*
Y719449D03*
Y714449D03*
Y709449D03*
Y704449D03*
Y699449D03*
Y694449D03*
Y689449D03*
Y684449D03*
Y679449D03*
Y674449D03*
Y669449D03*
Y664449D03*
Y734449D03*
Y1044961D03*
Y1039961D03*
Y1034961D03*
Y1029961D03*
Y1024961D03*
Y1019961D03*
Y1014961D03*
Y1139961D03*
Y1134961D03*
Y1129961D03*
Y1124961D03*
Y1119961D03*
Y1114961D03*
Y1109961D03*
Y1104961D03*
Y1099961D03*
Y1094961D03*
Y1089961D03*
Y1084961D03*
Y1079961D03*
Y1074961D03*
Y1069961D03*
Y1450473D03*
Y1445473D03*
Y1440473D03*
Y1435473D03*
Y1430473D03*
Y1425473D03*
Y1420473D03*
Y1545473D03*
Y1540473D03*
Y1535473D03*
Y1530473D03*
Y1525473D03*
Y1520473D03*
Y1515473D03*
Y1510473D03*
Y1505473D03*
Y1500473D03*
Y1495473D03*
Y1490473D03*
Y1485473D03*
Y1480473D03*
Y1475473D03*
Y1855985D03*
Y1850985D03*
Y1845985D03*
Y1840985D03*
Y1835985D03*
Y1830985D03*
Y1825985D03*
Y1885985D03*
Y1880985D03*
Y1950985D03*
Y1945985D03*
Y1940985D03*
Y1935985D03*
Y1930985D03*
Y1925985D03*
Y1920985D03*
Y1915985D03*
Y1910985D03*
Y1905985D03*
Y1900985D03*
Y1895985D03*
Y1890985D03*
X878937Y228937D03*
Y223937D03*
Y218937D03*
Y213937D03*
Y208937D03*
Y203937D03*
Y233937D03*
Y313937D03*
Y308937D03*
Y303937D03*
Y298937D03*
Y293937D03*
Y288937D03*
Y283937D03*
Y278937D03*
Y273937D03*
Y268937D03*
Y263937D03*
Y258937D03*
Y328937D03*
Y323937D03*
Y318937D03*
Y639449D03*
Y634449D03*
Y629449D03*
Y624449D03*
Y619449D03*
Y614449D03*
Y609449D03*
Y729449D03*
Y724449D03*
Y719449D03*
Y714449D03*
Y709449D03*
Y704449D03*
Y699449D03*
Y694449D03*
Y689449D03*
Y684449D03*
Y679449D03*
Y674449D03*
Y669449D03*
Y664449D03*
Y734449D03*
Y1044961D03*
Y1039961D03*
Y1034961D03*
Y1029961D03*
Y1024961D03*
Y1019961D03*
Y1014961D03*
Y1139961D03*
Y1134961D03*
Y1129961D03*
Y1124961D03*
Y1119961D03*
Y1114961D03*
Y1109961D03*
Y1104961D03*
Y1099961D03*
Y1094961D03*
Y1089961D03*
Y1084961D03*
Y1079961D03*
Y1074961D03*
Y1069961D03*
Y1450473D03*
Y1445473D03*
Y1440473D03*
Y1435473D03*
Y1430473D03*
Y1425473D03*
Y1420473D03*
Y1545473D03*
Y1540473D03*
Y1535473D03*
Y1530473D03*
Y1525473D03*
Y1520473D03*
Y1515473D03*
Y1510473D03*
Y1505473D03*
Y1500473D03*
Y1495473D03*
Y1490473D03*
Y1485473D03*
Y1480473D03*
Y1475473D03*
Y1855985D03*
Y1850985D03*
Y1845985D03*
Y1840985D03*
Y1835985D03*
Y1830985D03*
Y1825985D03*
Y1885985D03*
Y1880985D03*
Y1950985D03*
Y1945985D03*
Y1940985D03*
Y1935985D03*
Y1930985D03*
Y1925985D03*
Y1920985D03*
Y1915985D03*
Y1910985D03*
Y1905985D03*
Y1900985D03*
Y1895985D03*
Y1890985D03*
G54D50*
X20087Y1976300D03*
X946999Y118900D03*
G54D15*
X20700Y119500D03*
Y114500D03*
X180199Y95050D03*
X900699Y115050D03*
X890600Y1716200D03*
X878601Y1693850D03*
X965400Y1665500D03*
Y1660500D03*
G54D51*
X143999Y54089D03*
Y89011D03*
X862999Y60089D03*
Y95011D03*
G54D24*
X42449Y211775D03*
Y204025D03*
X49949Y207900D03*
X74049Y648025D03*
Y655775D03*
X66549Y651900D03*
X20849Y1059925D03*
Y1052175D03*
X28349Y1056050D03*
X60449Y1846475D03*
Y1838725D03*
X67949Y1842600D03*
X137249Y1347675D03*
Y1355425D03*
X129749Y1351550D03*
X193549Y157325D03*
Y165075D03*
X186049Y161200D03*
X193549Y564525D03*
Y572275D03*
X186049Y568400D03*
X193549Y968225D03*
Y975975D03*
X186049Y972100D03*
X208049Y1372925D03*
Y1380675D03*
X200549Y1376800D03*
X194049Y1778625D03*
Y1786375D03*
X186549Y1782500D03*
X922049Y563025D03*
Y570775D03*
X914549Y566900D03*
X922049Y967225D03*
Y974975D03*
X914549Y971100D03*
X856449Y1366675D03*
Y1358925D03*
X863949Y1362800D03*
X921549Y1777125D03*
Y1784875D03*
X914049Y1781000D03*
X939549Y163825D03*
Y171575D03*
X932049Y167700D03*
G54D60*
X171557Y533288D03*
X168997D03*
X166437D03*
X163877D03*
Y549468D03*
X166437D03*
X168997D03*
X171557D03*
X116045Y1484981D03*
X113485D03*
X110925D03*
X108365D03*
Y1501161D03*
X110925D03*
X113485D03*
X116045D03*
X833013Y176949D03*
X830453D03*
X827893D03*
X825333D03*
Y193129D03*
X827893D03*
X830453D03*
X833013D03*
Y1798997D03*
X830453D03*
X827893D03*
X825333D03*
Y1815177D03*
X827893D03*
X830453D03*
X833013D03*
G54D33*
X20300Y1097500D03*
Y1102500D03*
X242299Y76550D03*
X895300Y1721500D03*
X958299Y89550D03*
G54D42*
X49999Y1966250D03*
X143499Y517813D03*
X166499Y916313D03*
X136600Y1174600D03*
X107999Y1298313D03*
X109499Y1702813D03*
X218998Y312314D03*
X213598Y345314D03*
X218499Y719250D03*
X214599Y752250D03*
X217600Y1122200D03*
X217999Y1529250D03*
X218814Y1920313D03*
X213600Y1956800D03*
X297499Y86813D03*
X783049Y1813834D03*
X788049D03*
X858999Y306250D03*
X864900Y339300D03*
X855696Y706582D03*
X862896Y740782D03*
X855333Y1112092D03*
X862933Y1143592D03*
X857827Y1516996D03*
X865700Y1546800D03*
X857314Y1922813D03*
X864500Y1956600D03*
G54D52*
X154521Y132477D03*
Y107677D03*
X133521Y132477D03*
Y107677D03*
X861999Y139450D03*
Y114650D03*
X882499Y139450D03*
Y114650D03*
G54D70*
X336000Y1962500D03*
Y1971500D03*
G54D34*
X14700Y1097500D03*
Y1102500D03*
X236699Y76550D03*
X889700Y1721500D03*
X952699Y89550D03*
G54D43*
X18499Y1923750D03*
X134300Y455000D03*
X139499Y488813D03*
X162499Y886313D03*
X162999Y852813D03*
X104499Y1267813D03*
X103999Y1235250D03*
X102100Y1638700D03*
X105499Y1673313D03*
X221498Y281314D03*
X221499Y687750D03*
X217500Y1084200D03*
X253200Y1534900D03*
X220999Y1497750D03*
X227814Y1891313D03*
X293999Y56313D03*
X289099Y23313D03*
X853978Y275124D03*
X852696Y676082D03*
X852333Y1081592D03*
X854327Y1486496D03*
X894800Y1704200D03*
X854814Y1892313D03*
G54D25*
X46800Y412300D03*
X42900Y604800D03*
X30499Y1592060D03*
X23999Y1968250D03*
X31999Y1922250D03*
X27999Y1968250D03*
X174999Y74750D03*
X141499Y443813D03*
X146499D03*
X159199Y520550D03*
X167199D03*
X174199D03*
X136000Y532200D03*
X170499Y812313D03*
X166499D03*
X167499Y836813D03*
X172499D03*
X119000Y1136700D03*
X119499Y1109750D03*
X100500Y1107200D03*
X109499Y1201813D03*
X105499D03*
X106999Y1227313D03*
X111999D03*
X103999Y1472000D03*
X111499D03*
X115599Y1471950D03*
X152600Y1684600D03*
X135999Y1706750D03*
X131999D03*
X209499Y101250D03*
X217499D03*
X201499D03*
X185499Y120750D03*
X188000Y424200D03*
X211500Y822700D03*
X203500D03*
X184600Y1376500D03*
X180500D03*
X192800Y1654500D03*
X223436Y1897065D03*
X315000Y373700D03*
X313500Y1973700D03*
X644049Y1796334D03*
Y1807334D03*
X752978Y339124D03*
X751196Y738582D03*
X751499Y1143750D03*
X753827Y1546996D03*
X710549Y1801334D03*
X708549Y1812034D03*
X751000Y1950700D03*
X816499Y162750D03*
X823999D03*
X831499D03*
X765000Y355700D03*
X771500Y341200D03*
X826100Y670100D03*
X766000Y754700D03*
X770000Y742200D03*
X763000Y1158700D03*
X769500Y1145200D03*
X772000Y1549200D03*
X766500Y1561700D03*
X833499Y1783750D03*
X814999D03*
X824499D03*
X828000Y1884700D03*
X765000Y1964200D03*
X770000Y1952700D03*
X916499Y111750D03*
X900499Y88250D03*
X903499Y131750D03*
X940499Y111750D03*
X944499D03*
X924499D03*
X932499D03*
X952499D03*
G54D61*
X145000Y539050D03*
X141125Y531550D03*
X148875D03*
X129600Y1334250D03*
X125725Y1326750D03*
X133475D03*
X161700Y1689550D03*
X157825Y1682050D03*
X165575D03*
X183900Y925750D03*
X180025Y918250D03*
X187775D03*
X307000Y105150D03*
X303125Y97650D03*
X310875D03*
G54D16*
X26300Y119500D03*
Y114500D03*
X185799Y95050D03*
X906299Y115050D03*
X896200Y1716200D03*
X884201Y1693850D03*
X971000Y1665500D03*
Y1660500D03*
G54D62*
X156499Y1297113D03*
X161499D03*
X166499D03*
X171499D03*
Y1277113D03*
X166499D03*
X161499D03*
X156499D03*
X157499Y1720113D03*
X162499D03*
X167499D03*
X172499D03*
Y1700113D03*
X167499D03*
X162499D03*
X157499D03*
X191499Y534113D03*
X196499D03*
X201499D03*
X206499D03*
Y514113D03*
X201499D03*
X196499D03*
X191499D03*
X214999Y932613D03*
X219999D03*
X224999D03*
X229999D03*
Y912613D03*
X224999D03*
X219999D03*
X214999D03*
X247299Y1136650D03*
X242299D03*
X237299D03*
X232299D03*
Y1156650D03*
X237299D03*
X242299D03*
X247299D03*
X345999Y106550D03*
X350999D03*
X355999D03*
X360999D03*
Y86550D03*
X355999D03*
X350999D03*
X345999D03*
G54D35*
X84999Y1121050D03*
Y1126050D03*
Y1131050D03*
Y1136050D03*
X173999Y430050D03*
Y435050D03*
Y440050D03*
Y445050D03*
X104999Y1136050D03*
Y1131050D03*
Y1126050D03*
Y1121050D03*
X158499Y1226113D03*
Y1221113D03*
Y1216113D03*
X138499D03*
Y1221113D03*
Y1226113D03*
X158499Y1231113D03*
X138499D03*
X168499Y1625613D03*
Y1630613D03*
Y1635613D03*
Y1640613D03*
X253998Y295114D03*
Y300114D03*
Y305114D03*
Y310114D03*
X193999Y445050D03*
Y440050D03*
Y435050D03*
Y430050D03*
X254499Y701550D03*
Y706550D03*
Y711550D03*
Y716550D03*
X218499Y843613D03*
Y838613D03*
Y833613D03*
Y828613D03*
X198499D03*
Y833613D03*
Y838613D03*
Y843613D03*
X252999Y1513050D03*
Y1518050D03*
Y1523050D03*
Y1528050D03*
X188499Y1640613D03*
Y1635613D03*
Y1630613D03*
Y1625613D03*
X255777Y1917191D03*
Y1922191D03*
Y1927191D03*
Y1932191D03*
X273998Y310114D03*
Y305114D03*
Y300114D03*
Y295114D03*
X279999Y351050D03*
Y356050D03*
Y361050D03*
Y366050D03*
X299999D03*
Y361050D03*
Y356050D03*
Y351050D03*
X274499Y716550D03*
Y711550D03*
Y706550D03*
Y701550D03*
X280999Y757550D03*
Y762550D03*
Y767550D03*
Y772550D03*
X300999D03*
Y767550D03*
Y762550D03*
Y757550D03*
X272999Y1528050D03*
Y1523050D03*
Y1518050D03*
Y1513050D03*
X279999Y1568550D03*
Y1573550D03*
Y1578550D03*
Y1583550D03*
X299999D03*
Y1578550D03*
Y1573550D03*
Y1568550D03*
X275777Y1932191D03*
Y1927191D03*
Y1922191D03*
Y1917191D03*
X279777Y1961191D03*
Y1966191D03*
Y1971191D03*
X299777D03*
Y1966191D03*
Y1961191D03*
X279777Y1976191D03*
X299777D03*
X356499Y21550D03*
Y26550D03*
Y31550D03*
Y36550D03*
X376499D03*
Y31550D03*
Y26550D03*
Y21550D03*
X802873Y292471D03*
Y297471D03*
Y302471D03*
Y307471D03*
X822873D03*
Y302471D03*
Y297471D03*
Y292471D03*
X797978Y356924D03*
Y351924D03*
Y346924D03*
Y341924D03*
X777978D03*
Y346924D03*
Y351924D03*
Y356924D03*
X800831Y696853D03*
Y701853D03*
Y706853D03*
Y711853D03*
X820831D03*
Y706853D03*
Y701853D03*
Y696853D03*
X796696Y757382D03*
Y752382D03*
Y747382D03*
Y742382D03*
X776696D03*
Y747382D03*
Y752382D03*
Y757382D03*
X800841Y1101216D03*
Y1106216D03*
Y1111216D03*
Y1116216D03*
X820841D03*
Y1111216D03*
Y1106216D03*
Y1101216D03*
X796833Y1143892D03*
X776833D03*
X796833Y1158892D03*
Y1153892D03*
Y1148892D03*
X776833D03*
Y1153892D03*
Y1158892D03*
X802245Y1503722D03*
Y1508722D03*
Y1513722D03*
Y1518722D03*
X822245D03*
Y1513722D03*
Y1508722D03*
Y1503722D03*
X799327Y1553796D03*
Y1548796D03*
X779327D03*
Y1553796D03*
X799327Y1563796D03*
Y1558796D03*
X779327D03*
Y1563796D03*
X801436Y1910365D03*
Y1915365D03*
Y1920365D03*
Y1925365D03*
X821436D03*
Y1920365D03*
Y1915365D03*
Y1910365D03*
X796814Y1969713D03*
Y1964713D03*
Y1959713D03*
Y1954713D03*
X776814D03*
Y1959713D03*
Y1964713D03*
Y1969713D03*
G54D71*
X666399Y1806699D03*
Y1808664D03*
Y1810634D03*
Y1812604D03*
Y1814569D03*
X682699D03*
Y1812604D03*
Y1810634D03*
Y1808664D03*
Y1806699D03*
G54D44*
X18499Y1929350D03*
X134300Y460600D03*
X139499Y494413D03*
X162499Y891913D03*
X162999Y858413D03*
X104499Y1273413D03*
X103999Y1240850D03*
X105499Y1678913D03*
X102100Y1644300D03*
X221498Y286914D03*
X221499Y693350D03*
X217500Y1089800D03*
X253200Y1540500D03*
X220999Y1503350D03*
X227814Y1896913D03*
X293999Y61913D03*
X289099Y28913D03*
X853978Y280724D03*
X852696Y681682D03*
X852333Y1087192D03*
X854327Y1492096D03*
X894800Y1709800D03*
X854814Y1897913D03*
G54D53*
X130400Y420900D03*
X159500Y821800D03*
X177500Y1276800D03*
X122799Y1485350D03*
X178999Y74850D03*
X235499Y84850D03*
X213499Y101350D03*
X216998Y287414D03*
X184000Y424300D03*
X212000Y513300D03*
X216999Y693850D03*
X207500Y822800D03*
X222900Y1090100D03*
X216999Y1503850D03*
X253500Y1911300D03*
X232314Y1897413D03*
X327500Y354800D03*
X312800Y321100D03*
X308999Y728350D03*
X311000Y758300D03*
X309299Y1536750D03*
X313499Y1931850D03*
X366500Y86300D03*
X655549Y1796434D03*
Y1803934D03*
X755500Y709800D03*
X693549Y1801934D03*
Y1809434D03*
X816500Y286300D03*
X764500Y308300D03*
X779978Y308224D03*
X769000Y355800D03*
X810000Y690800D03*
X777500Y709800D03*
X816000Y1094300D03*
X760500Y1110800D03*
X778500D03*
X767000Y1158800D03*
X816000Y1497800D03*
X783200Y1516500D03*
X762000Y1516800D03*
X770500Y1561800D03*
X815500Y1904300D03*
X769000Y1964300D03*
X759500Y1922800D03*
X784500D03*
X904499Y88350D03*
X858478Y281224D03*
X857196Y682182D03*
X856833Y1087692D03*
X858827Y1492596D03*
X859314Y1898413D03*
X928499Y111850D03*
G54D26*
X46800Y408900D03*
X42900Y601400D03*
X30499Y1588660D03*
X23999Y1964850D03*
X31999Y1918850D03*
X27999Y1964850D03*
X174999Y71350D03*
X141499Y440413D03*
X146499D03*
X159199Y517150D03*
X167199D03*
X174199D03*
X136000Y528800D03*
X170499Y808913D03*
X166499D03*
X167499Y833413D03*
X172499D03*
X119000Y1133300D03*
X119499Y1106350D03*
X100500Y1103800D03*
X106999Y1223913D03*
X111999D03*
X109499Y1198413D03*
X105499D03*
X103999Y1468600D03*
X111499D03*
X115599Y1468550D03*
X152600Y1681200D03*
X135999Y1703350D03*
X131999D03*
X209499Y97850D03*
X217499D03*
X201499D03*
X185499Y117350D03*
X188000Y420800D03*
X211500Y819300D03*
X203500D03*
X184600Y1373100D03*
X180500D03*
X192800Y1651100D03*
X223436Y1893665D03*
X315000Y370300D03*
X313500Y1970300D03*
X644049Y1803934D03*
Y1792934D03*
X752978Y335724D03*
X751196Y735182D03*
X751499Y1140350D03*
X753827Y1543596D03*
X710549Y1797934D03*
X708549Y1808634D03*
X751000Y1947300D03*
X816499Y159350D03*
X823999D03*
X831499D03*
X765000Y352300D03*
X771500Y337800D03*
X826100Y666700D03*
X766000Y751300D03*
X770000Y738800D03*
X769500Y1141800D03*
X763000Y1155300D03*
X772000Y1545800D03*
X766500Y1558300D03*
X833499Y1780350D03*
X814999D03*
X824499D03*
X828000Y1881300D03*
X765000Y1960800D03*
X770000Y1949300D03*
X916499Y108350D03*
X900499Y84850D03*
X903499Y128350D03*
X940499Y108350D03*
X944499D03*
X924499D03*
X932499D03*
X952499D03*
G54D17*
X28000Y83750D03*
Y102250D03*
X27500Y921250D03*
Y902750D03*
X18500Y1067750D03*
Y1086250D03*
X42600Y1886050D03*
Y1867550D03*
X117999Y1143550D03*
Y1162050D03*
G54D27*
X42700Y408900D03*
X34000Y1058300D03*
X83000Y1548300D03*
X79000D03*
X34599Y1588650D03*
X75000Y1565200D03*
X79000D03*
X31999Y1964850D03*
X19999D03*
X27030Y1925238D03*
X49499Y1901850D03*
X23030Y1925238D03*
X31999Y1972350D03*
X162999Y443913D03*
X150999Y440413D03*
X176499Y833413D03*
X127000Y1133300D03*
X100500Y1111800D03*
X97499Y1086850D03*
X101999D03*
X127499Y1224413D03*
X116499Y1223913D03*
Y1321413D03*
X120507Y1321496D03*
X116749Y1510150D03*
X112599D03*
X174499Y1649663D03*
X205499Y97850D03*
X197499D03*
X185999Y496450D03*
X181899D03*
X185999Y842413D03*
X190499D03*
X205999Y898313D03*
X209999D03*
X226800Y1086600D03*
X247500Y1078550D03*
X225499Y1499350D03*
X203000Y1637800D03*
X231000Y1880500D03*
X236100Y1893900D03*
X307000Y370300D03*
X280499Y341850D03*
X284999D03*
X311000Y771300D03*
X281499Y748350D03*
X285499D03*
X310500Y1582800D03*
X278499Y1559350D03*
X282499D03*
X330000Y1969800D03*
X284358Y1951628D03*
X288358D03*
X363000Y42800D03*
X399999Y39350D03*
X640049Y1803934D03*
Y1792934D03*
X649049Y1810934D03*
X655549Y1815434D03*
X749500Y348300D03*
X750500Y747800D03*
X747500Y1151800D03*
X751000Y1553800D03*
X744049Y1802934D03*
Y1795434D03*
X706549Y1797934D03*
X744049Y1810434D03*
X712549Y1808634D03*
X749500Y1958300D03*
X833999Y204850D03*
X829499D03*
X827500Y267500D03*
X825700Y1075800D03*
X827700Y1480700D03*
X912499Y108350D03*
X920499D03*
X889700Y1704700D03*
X936499Y108350D03*
X948499D03*
G54D63*
X105749Y1964050D03*
X121249D03*
X221749Y39550D03*
X206249D03*
X915749Y44550D03*
X931249D03*
G54D45*
X37999Y1968750D03*
X65768Y1966462D03*
X74568D03*
X83568D03*
X57068D03*
X92568D03*
X37999Y1976350D03*
X65768Y1974062D03*
X74568D03*
X83568D03*
X57068D03*
X92568D03*
X240999Y89850D03*
Y82250D03*
G54D36*
X72999Y1871550D03*
Y1882550D03*
X63999Y1871050D03*
Y1882050D03*
X169999Y123550D03*
Y112550D03*
X178999Y123550D03*
Y112550D03*
X158999Y453113D03*
Y464113D03*
X149999Y453113D03*
Y464113D03*
X140999Y453113D03*
Y464113D03*
X167900Y453100D03*
Y464100D03*
X146499Y486613D03*
Y497613D03*
X178999Y851613D03*
Y862613D03*
X169999Y851613D03*
Y862613D03*
X169499Y885113D03*
Y896113D03*
X129900Y1182500D03*
Y1171500D03*
X102999Y1182550D03*
Y1171550D03*
X111999Y1182550D03*
Y1171550D03*
X120999Y1182550D03*
Y1171550D03*
X132700Y1265400D03*
Y1254400D03*
X129499Y1233613D03*
Y1244613D03*
X120499Y1233613D03*
Y1244613D03*
X111499Y1233613D03*
Y1244613D03*
Y1266613D03*
Y1277613D03*
X126199Y1638013D03*
X117500Y1638000D03*
X108799Y1638013D03*
X133999Y1670613D03*
Y1659613D03*
X126199Y1649013D03*
X117500Y1649000D03*
X108799Y1649013D03*
X112499Y1671613D03*
Y1682613D03*
X225900Y307400D03*
X246498Y319114D03*
Y330114D03*
X237698Y351614D03*
Y340614D03*
X228998Y351614D03*
Y340614D03*
X220298Y351614D03*
Y340614D03*
X225900Y318400D03*
X246499Y726050D03*
X225499D03*
Y715050D03*
X246499Y737050D03*
X238699Y760550D03*
Y749550D03*
X229999Y760550D03*
Y749550D03*
X221299Y760550D03*
Y749550D03*
X191499Y884113D03*
Y873113D03*
X187999Y851613D03*
Y862613D03*
X224300Y1130200D03*
Y1119200D03*
X246499Y1535550D03*
Y1546550D03*
X237700Y1557100D03*
X229000D03*
X220300D03*
X224999Y1535550D03*
Y1524550D03*
X237700Y1568100D03*
X229000D03*
X220300D03*
X246314Y1934113D03*
Y1945113D03*
X220300Y1964600D03*
Y1953600D03*
X229000Y1964600D03*
Y1953600D03*
X237700Y1964600D03*
Y1953600D03*
X225814Y1931113D03*
Y1920113D03*
X322499Y54613D03*
Y43613D03*
X314099Y22113D03*
Y33113D03*
X305099Y22113D03*
Y33113D03*
X296099Y22113D03*
Y33113D03*
X300999Y55613D03*
Y66613D03*
X832978Y313424D03*
Y324424D03*
X840800Y346800D03*
Y335800D03*
X830499Y715550D03*
Y726550D03*
X838796Y747582D03*
Y736582D03*
X830499Y1119550D03*
Y1130550D03*
X838833Y1141392D03*
Y1152392D03*
X833827Y1523796D03*
Y1534796D03*
X841500Y1556300D03*
Y1545300D03*
X840400Y1965000D03*
Y1954000D03*
X832499Y1930050D03*
Y1941050D03*
X846999Y135550D03*
Y124550D03*
X896999Y136550D03*
Y125550D03*
X850999Y312550D03*
Y301550D03*
X849500Y346800D03*
Y335800D03*
X858200Y346800D03*
Y335800D03*
X848696Y713882D03*
Y702882D03*
X847496Y747582D03*
Y736582D03*
X856196Y747582D03*
Y736582D03*
X847533Y1141392D03*
X856233D03*
X848413Y1118613D03*
Y1107613D03*
X847533Y1152392D03*
X856233D03*
X850200Y1556300D03*
Y1545300D03*
X858900Y1556300D03*
Y1545300D03*
X850827Y1523296D03*
Y1512296D03*
X849100Y1965000D03*
Y1954000D03*
X857800Y1965000D03*
Y1954000D03*
X850314Y1929113D03*
Y1918113D03*
G54D18*
X77166Y114212D03*
Y117362D03*
Y120511D03*
Y123661D03*
Y126811D03*
Y129960D03*
Y133110D03*
Y519724D03*
Y522874D03*
Y526023D03*
Y529173D03*
Y532323D03*
Y535472D03*
Y538622D03*
Y925236D03*
Y928386D03*
Y931535D03*
Y934685D03*
Y937835D03*
Y940984D03*
Y944134D03*
Y1330748D03*
Y1333898D03*
Y1337047D03*
Y1340197D03*
Y1343347D03*
Y1346496D03*
Y1349646D03*
Y1736260D03*
Y1739410D03*
Y1742559D03*
Y1745709D03*
Y1748859D03*
Y1752008D03*
Y1755158D03*
X159055Y255866D03*
Y252716D03*
Y249567D03*
Y246417D03*
Y243267D03*
Y240118D03*
Y236968D03*
Y645630D03*
Y642480D03*
Y661378D03*
Y658228D03*
Y655079D03*
Y651929D03*
Y648779D03*
Y1060591D03*
Y1057441D03*
Y1054291D03*
Y1051142D03*
Y1047992D03*
Y1066890D03*
Y1063740D03*
Y1472402D03*
Y1469252D03*
Y1466103D03*
Y1462953D03*
Y1459803D03*
Y1456654D03*
Y1453504D03*
Y1877914D03*
Y1874764D03*
Y1871615D03*
Y1868465D03*
Y1865315D03*
Y1862166D03*
Y1859016D03*
X887401Y255866D03*
Y252716D03*
Y249567D03*
Y246417D03*
Y243267D03*
Y240118D03*
Y236968D03*
Y645630D03*
Y642480D03*
Y661378D03*
Y658228D03*
Y655079D03*
Y651929D03*
Y648779D03*
Y1060591D03*
Y1057441D03*
Y1054291D03*
Y1051142D03*
Y1047992D03*
Y1066890D03*
Y1063740D03*
Y1472402D03*
Y1469252D03*
Y1466103D03*
Y1462953D03*
Y1459803D03*
Y1456654D03*
Y1453504D03*
Y1877914D03*
Y1874764D03*
Y1871615D03*
Y1868465D03*
Y1865315D03*
Y1862166D03*
Y1859016D03*
G54D72*
X753949Y1801294D03*
Y1803854D03*
Y1806414D03*
Y1808974D03*
X776149Y1803854D03*
Y1801294D03*
Y1808974D03*
Y1806414D03*
G54D54*
X130400Y417300D03*
X159500Y818200D03*
X177500Y1273200D03*
X122799Y1481750D03*
X178999Y71250D03*
X235499Y81250D03*
X213499Y97750D03*
X216998Y283814D03*
X184000Y420700D03*
X212000Y509700D03*
X216999Y690250D03*
X207500Y819200D03*
X222900Y1086500D03*
X216999Y1500250D03*
X253500Y1907700D03*
X232314Y1893813D03*
X327500Y351200D03*
X312800Y317500D03*
X308999Y724750D03*
X311000Y754700D03*
X309299Y1533150D03*
X313499Y1928250D03*
X366500Y82700D03*
X655549Y1792834D03*
Y1800334D03*
X755500Y706200D03*
X693549Y1798334D03*
Y1805834D03*
X816500Y282700D03*
X764500Y304700D03*
X779978Y304624D03*
X769000Y352200D03*
X810000Y687200D03*
X777500Y706200D03*
X816000Y1090700D03*
X760500Y1107200D03*
X778500D03*
X767000Y1155200D03*
X816000Y1494200D03*
X783200Y1512900D03*
X762000Y1513200D03*
X770500Y1558200D03*
X815500Y1900700D03*
X769000Y1960700D03*
X759500Y1919200D03*
X784500D03*
X904499Y84750D03*
X858478Y277624D03*
X857196Y678582D03*
X856833Y1084092D03*
X858827Y1488996D03*
X859314Y1894813D03*
X928499Y108250D03*
G54D28*
X42700Y412300D03*
X34000Y1061700D03*
X83000Y1551700D03*
X79000D03*
X34599Y1592050D03*
X75000Y1568600D03*
X79000D03*
X31999Y1968250D03*
X19999D03*
X27030Y1928638D03*
X49499Y1905250D03*
X23030Y1928638D03*
X31999Y1975750D03*
X162999Y447313D03*
X150999Y443813D03*
X176499Y836813D03*
X127000Y1136700D03*
X100500Y1115200D03*
X97499Y1090250D03*
X101999D03*
X127499Y1227813D03*
X116499Y1227313D03*
Y1324813D03*
X120507Y1324896D03*
X116749Y1513550D03*
X112599D03*
X174499Y1653063D03*
X205499Y101250D03*
X197499D03*
X185999Y499850D03*
X181899D03*
X185999Y845813D03*
X190499D03*
X205999Y901713D03*
X209999D03*
X226800Y1090000D03*
X247500Y1081950D03*
X225499Y1502750D03*
X203000Y1641200D03*
X231000Y1883900D03*
X236100Y1897300D03*
X307000Y373700D03*
X280499Y345250D03*
X284999D03*
X311000Y774700D03*
X281499Y751750D03*
X285499D03*
X310500Y1586200D03*
X278499Y1562750D03*
X282499D03*
X284358Y1955028D03*
X288358D03*
X330000Y1973200D03*
X363000Y46200D03*
X399999Y42750D03*
X640049Y1796334D03*
X649049Y1814334D03*
X655549Y1818834D03*
X640049Y1807334D03*
X749500Y351700D03*
X750500Y751200D03*
X747500Y1155200D03*
X751000Y1557200D03*
X744049Y1798834D03*
X706549Y1801334D03*
X744049Y1813834D03*
Y1806334D03*
X712549Y1812034D03*
X749500Y1961700D03*
X833999Y208250D03*
X829499D03*
X827500Y270900D03*
X825700Y1079200D03*
X827700Y1484100D03*
X912499Y111750D03*
X920499D03*
X889700Y1708100D03*
X936499Y111750D03*
X948499D03*
G54D37*
X43999Y1964750D03*
X138999Y517313D03*
X161999Y915813D03*
X123000Y1133200D03*
X142667Y1306460D03*
X132999Y1306813D03*
X103499Y1297813D03*
X178500Y1697700D03*
X104999Y1702063D03*
X137504Y1735523D03*
X123999Y1734813D03*
X182499Y71250D03*
X194500Y499200D03*
X236000Y908200D03*
X215900Y896900D03*
X199000Y1637700D03*
X292999Y86313D03*
X311000Y370200D03*
X295500Y329200D03*
X307000Y771200D03*
X298000Y735700D03*
X297000Y1549800D03*
X327000Y1570700D03*
X306500Y1582700D03*
X309300Y1970276D03*
X296858Y1944028D03*
X367000Y42700D03*
X389500Y72200D03*
X369300Y72300D03*
X693549Y1813334D03*
X770000Y751200D03*
X907999Y84750D03*
X870201Y1709850D03*
G54D46*
X44368Y1946712D03*
G54D19*
X71773Y209631D03*
Y206431D03*
X66023Y209631D03*
Y206431D03*
X71773Y615143D03*
Y611943D03*
X66023Y615143D03*
Y611943D03*
X71773Y1020655D03*
Y1017455D03*
X66023Y1020655D03*
Y1017455D03*
X71773Y1426167D03*
Y1422967D03*
X66023Y1426167D03*
Y1422967D03*
X71773Y1831679D03*
Y1828479D03*
X66023Y1831679D03*
Y1828479D03*
X164448Y160447D03*
Y163647D03*
X170198Y160447D03*
Y163647D03*
X164448Y565959D03*
Y569159D03*
X170198Y565959D03*
Y569159D03*
X164448Y971471D03*
Y974671D03*
X170198Y971471D03*
Y974671D03*
X164448Y1376983D03*
Y1380183D03*
X170198Y1376983D03*
Y1380183D03*
X164448Y1782494D03*
Y1785694D03*
X170198Y1782494D03*
Y1785694D03*
X892794Y160447D03*
Y163647D03*
X898544Y160447D03*
Y163647D03*
X892794Y565959D03*
Y569159D03*
X898544Y565959D03*
Y569159D03*
X892794Y971471D03*
Y974671D03*
X898544Y971471D03*
Y974671D03*
X892794Y1376983D03*
Y1380183D03*
X898544Y1376983D03*
Y1380183D03*
X892794Y1782494D03*
Y1785694D03*
X898544Y1782494D03*
Y1785694D03*
G54D73*
X825300Y1726200D03*
X836300D03*
X887700Y1733800D03*
X876700D03*
X940400Y1486900D03*
X951400D03*
X940500Y1477500D03*
X951500D03*
G54D55*
X158299Y438173D03*
Y435613D03*
Y433053D03*
X165699D03*
Y435613D03*
Y438173D03*
X113499Y1106640D03*
Y1109200D03*
Y1111760D03*
X106099D03*
Y1109200D03*
Y1106640D03*
X123299Y1218673D03*
Y1216113D03*
Y1213553D03*
X130699D03*
Y1216113D03*
Y1218673D03*
X147400Y1324540D03*
Y1327100D03*
Y1329660D03*
X140000D03*
Y1327100D03*
Y1324540D03*
X181799Y836673D03*
Y834113D03*
Y831553D03*
X189199D03*
Y834113D03*
Y836673D03*
X242000Y1069000D03*
Y1071560D03*
Y1074120D03*
X234600D03*
Y1071560D03*
Y1069000D03*
X233600Y1473240D03*
X241000D03*
X233600Y1478360D03*
Y1475800D03*
X241000D03*
Y1478360D03*
X179999Y1652987D03*
Y1650427D03*
Y1647867D03*
X187399D03*
Y1650427D03*
Y1652987D03*
X218100Y1882960D03*
Y1880400D03*
Y1877840D03*
X225500D03*
Y1880400D03*
Y1882960D03*
X324800Y92340D03*
Y94900D03*
Y97460D03*
X317400D03*
Y94900D03*
Y92340D03*
X394199Y36490D03*
Y39050D03*
Y41610D03*
X386799D03*
Y39050D03*
Y36490D03*
X758778Y341984D03*
Y339424D03*
Y336864D03*
X756996Y742442D03*
Y739882D03*
Y737322D03*
X756799Y1141490D03*
Y1146610D03*
Y1144050D03*
X757114Y1954773D03*
Y1952213D03*
Y1949653D03*
X814700Y270060D03*
Y267500D03*
Y264940D03*
X822100D03*
Y267500D03*
Y270060D03*
X766178Y336864D03*
Y339424D03*
Y341984D03*
X813200Y672660D03*
Y670100D03*
Y667540D03*
X820600D03*
Y670100D03*
Y672660D03*
X764396Y737322D03*
Y739882D03*
Y742442D03*
X764199Y1141490D03*
X812900Y1075460D03*
Y1072900D03*
Y1070340D03*
X820300D03*
Y1072900D03*
Y1075460D03*
X764199Y1144050D03*
Y1146610D03*
X759127Y1549356D03*
Y1546796D03*
Y1544236D03*
X766527D03*
Y1546796D03*
Y1549356D03*
X814700Y1483160D03*
Y1480600D03*
Y1478040D03*
X822100D03*
Y1480600D03*
Y1483160D03*
X815300Y1887560D03*
Y1885000D03*
Y1882440D03*
X822700D03*
Y1885000D03*
Y1887560D03*
X764514Y1949653D03*
Y1952213D03*
Y1954773D03*
G54D64*
X210676Y72528D03*
X928499Y85550D03*
G54D38*
X43999Y1968350D03*
X138999Y520913D03*
X161999Y919413D03*
X123000Y1136800D03*
X103499Y1301413D03*
X142667Y1310060D03*
X132999Y1310413D03*
X178500Y1701300D03*
X104999Y1705663D03*
X137504Y1739123D03*
X123999Y1738413D03*
X182499Y74850D03*
X194500Y502800D03*
X236000Y911800D03*
X215900Y900500D03*
X199000Y1641300D03*
X292999Y89913D03*
X311000Y373800D03*
X295500Y332800D03*
X307000Y774800D03*
X298000Y739300D03*
X297000Y1553400D03*
X327000Y1574300D03*
X306500Y1586300D03*
X296858Y1947628D03*
X309300Y1973876D03*
X367000Y46300D03*
X389500Y75800D03*
X369300Y75900D03*
X693549Y1816934D03*
X770000Y754800D03*
X907999Y88350D03*
X870201Y1713450D03*
G54D29*
X69400Y719500D03*
X44600D03*
X91099Y1890550D03*
Y1870050D03*
X125300Y1582500D03*
X100500D03*
X115899Y1890550D03*
Y1870050D03*
G54D47*
X34525Y1956355D03*
X36494D03*
X38462D03*
X40431D03*
X42399D03*
X44368D03*
X46337D03*
X48305D03*
X50274D03*
X52242D03*
X54211D03*
Y1937069D03*
X52242D03*
X50274D03*
X48305D03*
X46337D03*
X44368D03*
X42399D03*
X40431D03*
X38462D03*
X36494D03*
X34525D03*
G54D65*
X220319Y66622D03*
Y64654D03*
Y62685D03*
X201033D03*
Y64654D03*
Y66622D03*
X220319Y82371D03*
Y80402D03*
Y78434D03*
Y76465D03*
Y74497D03*
Y72528D03*
Y70559D03*
Y68591D03*
X201033D03*
Y70559D03*
Y72528D03*
Y74497D03*
Y76465D03*
Y78434D03*
Y80402D03*
Y82371D03*
X918856Y75707D03*
Y77676D03*
Y79644D03*
Y81613D03*
Y83581D03*
Y85550D03*
Y87519D03*
Y89487D03*
Y91456D03*
Y93424D03*
Y95393D03*
X938142D03*
Y93424D03*
Y91456D03*
Y89487D03*
Y87519D03*
Y85550D03*
Y83581D03*
Y81613D03*
Y79644D03*
Y77676D03*
Y75707D03*
G54D74*
X876000Y1703899D03*
X879750D03*
X883500D03*
Y1714499D03*
X879750D03*
X876000D03*
G54D56*
X140749Y474550D03*
X159249D03*
X140999Y508113D03*
X159499D03*
X164249Y873113D03*
Y906613D03*
X105749Y1288613D03*
X124249D03*
X105749Y1255113D03*
X124249D03*
X107249Y1693113D03*
X125749D03*
X106749Y1659613D03*
X125249D03*
X219248Y296614D03*
X237748D03*
X219248Y329614D03*
X237748D03*
X219749Y703050D03*
X238249D03*
X219249Y737050D03*
X237749D03*
X182749Y873113D03*
Y906613D03*
X219250Y1103100D03*
X237750D03*
X218050Y1513400D03*
X236550D03*
X219249Y1546050D03*
X237749D03*
X219684Y1906687D03*
X238184D03*
X218184Y1942987D03*
X236684D03*
X295249Y43613D03*
X313749D03*
X295249Y77113D03*
X313749D03*
X837978Y290124D03*
X841478Y323924D03*
X836196Y691182D03*
X839249Y724550D03*
X836333Y1096692D03*
X839749Y1129550D03*
X838077Y1501596D03*
X838314Y1907313D03*
X841249Y1940550D03*
X856478Y290124D03*
X859978Y323924D03*
X854696Y691182D03*
X857749Y724550D03*
X854833Y1096692D03*
X858249Y1129550D03*
X856577Y1501596D03*
X861077Y1534296D03*
X842577D03*
X856814Y1907313D03*
X859749Y1940550D03*
G54D75*
X854101Y1710351D03*
Y1733149D03*
G54D57*
X145439Y426863D03*
X147999D03*
X150559D03*
Y433363D03*
X145439D03*
X167439Y820363D03*
X169999D03*
X172559D03*
Y826863D03*
X167439D03*
X109439Y1079300D03*
X111999D03*
X114559D03*
Y1085800D03*
X109439D03*
X106939Y1210363D03*
X109499D03*
X112059D03*
Y1216863D03*
X106939D03*
X114939Y1305300D03*
X120059D03*
Y1311800D03*
X117499D03*
X114939D03*
X132939Y1714800D03*
X135499D03*
X138059D03*
Y1721300D03*
X132939D03*
X208559Y891800D03*
X205999D03*
X203439D03*
Y885300D03*
X208559D03*
X284059Y333800D03*
X281499D03*
X278939D03*
Y327300D03*
X284059D03*
X285059Y740300D03*
X282499D03*
X279939D03*
Y733800D03*
X285059D03*
X284059Y1551300D03*
X281499D03*
X278939D03*
Y1544800D03*
X284059D03*
X288709Y1942700D03*
X286149D03*
X283589D03*
Y1936200D03*
X288709D03*
X790559Y327800D03*
X787999D03*
X785439D03*
Y321300D03*
X790559D03*
X790059Y728800D03*
X787499D03*
X784939D03*
Y722300D03*
X790059D03*
X789559Y1131800D03*
X786999D03*
X784439D03*
Y1125300D03*
X789559D03*
X792813Y1535628D03*
X790253D03*
X787693D03*
Y1529128D03*
X792813D03*
X791059Y1942300D03*
X788499D03*
X785939D03*
Y1935800D03*
X791059D03*
G54D48*
X76038Y1929550D03*
X110960D03*
G54D39*
X18199Y1956050D03*
X36199Y1918050D03*
X100699Y145050D03*
Y141550D03*
X105199Y129550D03*
Y126050D03*
X100645Y550988D03*
Y547488D03*
X101145Y525988D03*
Y522488D03*
X178399Y524850D03*
X102745Y956489D03*
Y952989D03*
X99745Y931489D03*
Y927989D03*
X119200Y1113500D03*
X129150Y1081100D03*
Y1077600D03*
X104028Y1361952D03*
Y1358452D03*
X100528Y1336952D03*
Y1333452D03*
X103699Y1767550D03*
Y1764050D03*
X101699Y1743050D03*
Y1739550D03*
X179699Y99050D03*
X697749Y1813134D03*
X835699Y167550D03*
X836199Y1788050D03*
X903699Y124550D03*
X951199Y96050D03*
G54D66*
X238149Y102050D03*
G54D58*
X140940Y550300D03*
X143500D03*
X146060D03*
Y557700D03*
X143500D03*
X140940D03*
X172240Y1678400D03*
X174800D03*
X177360D03*
Y1685800D03*
X174800D03*
X172240D03*
X242040Y275100D03*
X244600D03*
X247160D03*
Y282500D03*
X244600D03*
X242040D03*
X241440Y682500D03*
X244000D03*
X246560D03*
Y689900D03*
X244000D03*
X241440D03*
X181340Y937100D03*
X183900D03*
X186460D03*
Y944500D03*
X183900D03*
X181340D03*
X315939Y352350D03*
X318499D03*
X321059D03*
Y359750D03*
X318499D03*
X315939D03*
X316939Y759350D03*
X319499D03*
X322059D03*
Y766750D03*
X319499D03*
X316939D03*
X315939Y1569850D03*
X318499D03*
X321059D03*
Y1577250D03*
X318499D03*
X315939D03*
X319080Y1959072D03*
X321640D03*
X324200D03*
Y1966472D03*
X321640D03*
X319080D03*
G54D49*
X20087Y1973600D03*
X946999Y116200D03*
G54D67*
X240849Y102050D03*
G54D76*
X1005807Y1636102D03*
Y1631102D03*
Y1626102D03*
Y1621102D03*
Y1676102D03*
Y1671102D03*
Y1666102D03*
Y1661102D03*
Y1656102D03*
Y1651102D03*
Y1646102D03*
Y1641102D03*
G54D77*
G01X-71137Y-139897D02*
Y-219897D01*
G01D02*
X1129963D01*
G01X-75137Y-123897D02*
G02I-12000J0D01*
G01X-80287D02*
G02I-6850J0D01*
G01X-87137Y-139897D02*
Y-107897D01*
G01X-71137Y-123897D02*
X-103137D01*
G01X-71137Y-139897D02*
X1129963D01*
G01X-71137Y-175397D02*
X1129963D01*
G01X342463Y-139897D02*
Y-219897D01*
G01X479963Y-139897D02*
Y-219897D01*
G01X594963Y-139897D02*
Y-219897D01*
G01X762463Y-139897D02*
Y-219897D01*
G01X932463Y-139897D02*
Y-219897D01*
G01X1129963Y-139897D02*
Y-219897D01*
G01X1157963Y-123897D02*
G02I-12000J0D01*
G01X1152813D02*
G02I-6850J0D01*
G01X1145963Y-139897D02*
Y-107897D01*
G01X1161963Y-123897D02*
X1129963D01*
G54D68*
X231500Y269350D03*
X235375Y276850D03*
X227625D03*
X230900Y676250D03*
X234775Y683750D03*
X227025D03*
X232700Y1485950D03*
X236575Y1493450D03*
X228825D03*
X240100Y1880450D03*
X243975Y1887950D03*
X236225D03*
X836700Y267450D03*
X840575Y274950D03*
X832825D03*
X835300Y670150D03*
X839175Y677650D03*
X831425D03*
X835000Y1075750D03*
X838875Y1083250D03*
X831125D03*
X836900Y1479050D03*
X840775Y1486550D03*
X833025D03*
X837499Y1884800D03*
X833624Y1892300D03*
X841374D03*
G54D59*
X176999Y490913D03*
Y488353D03*
Y485793D03*
X116249Y1093990D03*
Y1096550D03*
Y1099110D03*
X109749D03*
Y1093990D03*
X117249Y1720110D03*
Y1717550D03*
Y1714990D03*
X123749D03*
Y1720110D03*
X183499Y485793D03*
Y490913D03*
X321748Y334054D03*
Y336614D03*
Y339174D03*
X315248D03*
Y334054D03*
X323249Y740990D03*
Y743550D03*
Y746110D03*
X316749D03*
Y740990D03*
X319749Y1554490D03*
Y1557050D03*
X313249Y1554490D03*
X319749Y1559610D03*
X313249D03*
X326971Y1944349D03*
Y1946909D03*
Y1949469D03*
X320471D03*
Y1944349D03*
X347749Y67110D03*
Y64550D03*
Y61990D03*
X354249D03*
Y67110D03*
X387749Y56110D03*
Y53550D03*
Y50990D03*
X394249D03*
Y56110D03*
X767728Y323864D03*
Y326424D03*
Y328984D03*
X761228D03*
Y323864D03*
X766946Y724822D03*
Y727382D03*
X760446Y724822D03*
X766946Y729942D03*
X760446D03*
X767083Y1126332D03*
Y1128892D03*
Y1131452D03*
X760583D03*
Y1126332D03*
X770077Y1531236D03*
Y1533796D03*
Y1536356D03*
X763577D03*
Y1531236D03*
X766564Y1937153D03*
Y1939713D03*
Y1942273D03*
X760064D03*
Y1937153D03*
G54D78*
G01X-89222Y-207897D02*
Y-190397D01*
G01X-80052D02*
Y-207897D01*
G01Y-199147D02*
X-89222D01*
G01X-67137Y-207897D02*
X-68447Y-207605D01*
X-69757Y-206439D01*
X-70631Y-204397D01*
X-71067Y-202064D01*
X-70631Y-199730D01*
X-69757Y-197689D01*
X-68447Y-196522D01*
X-67137Y-196231D01*
X-65827Y-196522D01*
X-64517Y-197689D01*
X-63644Y-199730D01*
X-63425Y-202064D01*
X-63644Y-204397D01*
X-64517Y-206439D01*
X-65827Y-207605D01*
X-67137Y-207897D01*
G01X-53349D02*
Y-196231D01*
G01Y-199147D02*
X-52475Y-197689D01*
X-51165Y-196522D01*
X-49419Y-196231D01*
X-47891Y-196522D01*
X-46580Y-197689D01*
X-45925Y-199730D01*
Y-207897D01*
G01X-35412Y-200022D02*
X-28425D01*
X-29080Y-197980D01*
X-30172Y-196814D01*
X-31700Y-196231D01*
X-33229Y-196522D01*
X-34539Y-197397D01*
X-35412Y-199439D01*
X-35849Y-201189D01*
Y-202939D01*
X-35412Y-204689D01*
X-34320Y-206439D01*
X-33010Y-207605D01*
X-31482Y-207897D01*
X-29954Y-207314D01*
X-28425Y-205564D01*
G01X-19222Y-213147D02*
X-17912Y-213730D01*
X-16165Y-213147D01*
X-15074Y-211981D01*
X-14200Y-210522D01*
X-12891Y-205856D01*
X-10052Y-196231D01*
G01X-17039D02*
X-12891Y-205856D01*
G01X22109Y-198564D02*
X22983Y-197689D01*
X23638Y-196231D01*
X24075Y-194188D01*
X23638Y-192439D01*
X22765Y-191272D01*
X21236Y-190397D01*
X15341D01*
Y-207897D01*
X22546D01*
X24075Y-206731D01*
X24948Y-204980D01*
X25385Y-202939D01*
X24948Y-200897D01*
X23638Y-199147D01*
X22109Y-198564D01*
X15341D01*
G01X41793Y-207897D02*
Y-196231D01*
G01Y-198272D02*
X40920Y-197106D01*
X39609Y-196522D01*
X38081Y-196231D01*
X36553Y-196814D01*
X35243Y-197980D01*
X34369Y-199730D01*
X33933Y-202064D01*
X34369Y-204397D01*
X35243Y-206147D01*
X36553Y-207314D01*
X38081Y-207897D01*
X39609Y-207605D01*
X40920Y-206731D01*
X41793Y-205564D01*
G01X59293Y-190397D02*
Y-207897D01*
G01Y-205273D02*
X58420Y-206731D01*
X57109Y-207605D01*
X55581Y-207897D01*
X53835Y-207314D01*
X52525Y-205856D01*
X51651Y-204106D01*
X51433Y-202064D01*
X51651Y-200022D01*
X52525Y-198272D01*
X53835Y-196814D01*
X55581Y-196231D01*
X57109Y-196522D01*
X58201Y-197106D01*
X59293Y-198272D01*
G01X69806Y-212272D02*
X71335Y-213439D01*
X73081Y-213730D01*
X74609Y-213439D01*
X75920Y-211981D01*
X76793Y-209939D01*
Y-196231D01*
G01Y-198564D02*
X75920Y-197397D01*
X74609Y-196522D01*
X73081Y-196231D01*
X71335Y-196814D01*
X70243Y-197980D01*
X69369Y-200022D01*
X68933Y-202064D01*
X69151Y-203814D01*
X70025Y-205856D01*
X71335Y-207314D01*
X73081Y-207897D01*
X74391Y-207605D01*
X75920Y-206439D01*
X76793Y-205273D01*
G01X87088Y-200022D02*
X94075D01*
X93420Y-197980D01*
X92328Y-196814D01*
X90800Y-196231D01*
X89271Y-196522D01*
X87961Y-197397D01*
X87088Y-199439D01*
X86651Y-201189D01*
Y-202939D01*
X87088Y-204689D01*
X88180Y-206439D01*
X89490Y-207605D01*
X91018Y-207897D01*
X92546Y-207314D01*
X94075Y-205564D01*
G01X104806Y-207897D02*
Y-196231D01*
G01Y-198564D02*
X105898Y-197397D01*
X106990Y-196522D01*
X108518Y-196231D01*
X109609Y-196522D01*
X110920Y-197397D01*
G01X138060Y-207897D02*
Y-190397D01*
X142426D01*
X144173Y-191272D01*
X145483Y-192439D01*
X146575Y-194188D01*
X147448Y-196231D01*
X147666Y-199147D01*
X147448Y-202064D01*
X146575Y-204106D01*
X145483Y-205856D01*
X144173Y-207022D01*
X142426Y-207897D01*
X138060D01*
G01X155996D02*
Y-190397D01*
X161236D01*
X162983Y-191272D01*
X164293Y-193314D01*
X164730Y-195647D01*
X164293Y-197980D01*
X163201Y-199730D01*
X161236Y-200606D01*
X155996D01*
G01X179609Y-198564D02*
X180483Y-197689D01*
X181138Y-196231D01*
X181575Y-194188D01*
X181138Y-192439D01*
X180265Y-191272D01*
X178736Y-190397D01*
X172841D01*
Y-207897D01*
X180046D01*
X181575Y-206731D01*
X182448Y-204980D01*
X182885Y-202939D01*
X182448Y-200897D01*
X181138Y-199147D01*
X179609Y-198564D01*
X172841D01*
G01X208496Y-190397D02*
Y-207897D01*
X217230D01*
G01X230363D02*
X229053Y-207605D01*
X227743Y-206439D01*
X226869Y-204397D01*
X226433Y-202064D01*
X226869Y-199730D01*
X227743Y-197689D01*
X229053Y-196522D01*
X230363Y-196231D01*
X231673Y-196522D01*
X232983Y-197689D01*
X233856Y-199730D01*
X234075Y-202064D01*
X233856Y-204397D01*
X232983Y-206439D01*
X231673Y-207605D01*
X230363Y-207897D01*
G01X242404Y-196231D02*
X245025Y-207897D01*
X247863Y-196231D01*
X250701Y-207897D01*
X253322Y-196231D01*
G01X278496Y-190397D02*
Y-207897D01*
X287230D01*
G01X300363D02*
X299053Y-207605D01*
X297743Y-206439D01*
X296869Y-204397D01*
X296433Y-202064D01*
X296869Y-199730D01*
X297743Y-197689D01*
X299053Y-196522D01*
X300363Y-196231D01*
X301673Y-196522D01*
X302983Y-197689D01*
X303856Y-199730D01*
X304075Y-202064D01*
X303856Y-204397D01*
X302983Y-206439D01*
X301673Y-207605D01*
X300363Y-207897D01*
G01X314588Y-205856D02*
X315680Y-207022D01*
X317208Y-207897D01*
X318518D01*
X319828Y-207314D01*
X320701Y-206439D01*
X321138Y-205273D01*
X320920Y-203522D01*
X320046Y-202647D01*
X316116Y-200897D01*
X315243Y-198855D01*
X315680Y-197397D01*
X316553Y-196522D01*
X317863Y-196231D01*
X319173Y-196522D01*
X320483Y-197397D01*
G01X332088Y-205856D02*
X333180Y-207022D01*
X334708Y-207897D01*
X336018D01*
X337328Y-207314D01*
X338201Y-206439D01*
X338638Y-205273D01*
X338420Y-203522D01*
X337546Y-202647D01*
X333616Y-200897D01*
X332743Y-198855D01*
X333180Y-197397D01*
X334053Y-196522D01*
X335363Y-196231D01*
X336673Y-196522D01*
X337983Y-197397D01*
G01X-78741Y15000D02*
G03X-63741Y0I15000J0D01*
G01X-78741Y15000D02*
Y120047D01*
G01X-63741Y135047D02*
G03X-78741Y120047I0J-15000D01*
G01Y298866D02*
G03X-63741Y283866I15000J0D01*
G01X-78741Y319646D02*
Y298866D01*
G01X-63741Y334646D02*
G03X-78741Y319646I0J-15000D01*
G01Y908315D02*
G03X-63741Y893315I15000J0D01*
G01X-78741Y908315D02*
Y1104299D01*
G01X-63741Y1119299D02*
G03X-78741Y1104299I0J-15000D01*
G01Y1283118D02*
G03X-63741Y1268118I15000J0D01*
G01X-78741Y1304285D02*
Y1283118D01*
G01X-63741Y1319285D02*
G03X-78741Y1304285I0J-15000D01*
G01Y1892953D02*
G03X-63741Y1877953I15000J0D01*
G01X-78741Y1892953D02*
Y1977126D01*
G01X-63741Y1992126D02*
G03X-78741Y1977126I0J-15000D01*
G01X19882Y1197834D02*
X1969D01*
X0Y1195865D01*
Y832479D01*
X1969Y830511D01*
X19882D01*
G02Y823030I0J-3741D01*
G01X1969D01*
X0Y821062D01*
Y423030D01*
X1969Y421062D01*
X19882D01*
G02Y413582I0J-3740D01*
G01X1969D01*
X0Y411613D01*
Y223030D01*
X1969Y221062D01*
X19882D01*
G02Y213582I0J-3740D01*
G01X1969D01*
X0Y211613D01*
Y3936D01*
G03X3937Y-1I3937J0D01*
G01X1029528D01*
G03X1033465Y3936I0J3937D01*
G01Y1424881D01*
X1029528Y1428818D01*
X1024213D01*
G02X1019291Y1433739I-1J4921D01*
G01Y1607932D01*
X1015354Y1611869D01*
X989744D01*
G02Y1616082I0J2107D01*
G01X1015354D01*
X1019291Y1620019D01*
Y1676495D01*
G02X1024213Y1681416I4921J0D01*
G01X1029528D01*
X1033465Y1685353D01*
Y1988188D01*
G03X1029528Y1992125I-3937J0D01*
G01X3937D01*
G03X0Y1988188I0J-3937D01*
G01Y1816731D01*
X1969Y1814763D01*
X19882D01*
G02Y1807282I0J-3741D01*
G01X1969D01*
X0Y1805314D01*
Y1407282D01*
X1969Y1405314D01*
X19882D01*
G02Y1397834I0J-3740D01*
G01X1969D01*
X0Y1395865D01*
Y1207282D01*
X1969Y1205314D01*
X19882D01*
G02Y1197834I0J-3740D01*
G01X-7875Y0D02*
X-63741D01*
G01X-7875Y41772D02*
Y104969D01*
G01Y17252D02*
Y0D01*
G01Y41772D02*
G03X-1I3937J-1D01*
G01Y17213D02*
G03X-7875I-3937J0D01*
G01Y41772D02*
G03X-1I3937J-1D01*
G01Y17213D02*
G03X-7875I-3937J0D01*
G01Y129516D02*
Y135047D01*
G01D02*
X-63741D01*
G01X-7875Y129516D02*
G03X-1I3937J0D01*
G01Y104958D02*
G03X-7875I-3937J0D01*
G01Y283866D02*
Y300383D01*
G01X-19814Y283866D02*
X-63741D01*
G01X-7875D02*
X-19814D01*
G01X-1Y300383D02*
G03X-7875I-3937J0D01*
G01Y331986D02*
Y324003D01*
G01Y331986D02*
Y334646D01*
G01D02*
X-63741D01*
G01X-7875Y324003D02*
G03X-1I3937J0D01*
G01X-7875Y905988D02*
Y893315D01*
G01D02*
X-63741D01*
G01X-7875Y1069005D02*
Y933234D01*
G01D02*
G03X-1I3937J0D01*
G01Y905988D02*
G03X-7875I-3937J0D01*
G01Y1108863D02*
Y1119299D01*
G01X-19126D02*
X-7875D01*
G01X-15749D02*
X-63741D01*
G01X-7875Y1106300D02*
Y1111425D01*
G01Y1106300D02*
Y1092625D01*
G01D02*
G03X-1I3937J0D01*
G01Y1069005D02*
G03X-7875I-3937J0D01*
G01X-17894Y1268118D02*
X-7875D01*
G01Y1278280D02*
Y1268118D01*
G01Y1280567D02*
Y1275992D01*
G01X-15749Y1268118D02*
X-63741D01*
G01X-7875Y1309889D02*
G03X-1I3937J0D01*
G01Y1280567D02*
G03X-7875I-3937J0D01*
G01Y1309889D02*
G03X-1I3937J0D01*
G01Y1280567D02*
G03X-7875I-3937J0D01*
G01Y1309889D02*
Y1319285D01*
G01D02*
X-63741D01*
G01X-7875Y1889223D02*
Y1877953D01*
G01D02*
X-63741D01*
G01X-7875Y1912843D02*
Y1962926D01*
G01Y1912843D02*
G03X-1I3937J0D01*
G01Y1889223D02*
G03X-7875I-3937J0D01*
G01Y1912843D02*
G03X-1I3937J0D01*
G01Y1889223D02*
G03X-7875I-3937J0D01*
G01X-1Y1962926D02*
G03X-7875I-3937J0D01*
G01X-1D02*
G03X-7875I-3937J0D01*
G01Y1986546D02*
Y1992126D01*
G01D02*
X-63741D01*
G01X-7875Y1986546D02*
G03X-1I3937J0D01*
G01X-7875D02*
G03X-1I3937J0D01*
G01X94686Y-164897D02*
Y-147397D01*
X100363Y-161980D01*
X106040Y-147397D01*
Y-164897D01*
G01X117863D02*
X116553Y-164605D01*
X115243Y-163439D01*
X114369Y-161397D01*
X113933Y-159064D01*
X114369Y-156730D01*
X115243Y-154689D01*
X116553Y-153522D01*
X117863Y-153231D01*
X119173Y-153522D01*
X120483Y-154689D01*
X121356Y-156730D01*
X121575Y-159064D01*
X121356Y-161397D01*
X120483Y-163439D01*
X119173Y-164605D01*
X117863Y-164897D01*
G01X139293Y-147397D02*
Y-164897D01*
G01Y-162273D02*
X138420Y-163731D01*
X137109Y-164605D01*
X135581Y-164897D01*
X133835Y-164314D01*
X132525Y-162856D01*
X131651Y-161106D01*
X131433Y-159064D01*
X131651Y-157022D01*
X132525Y-155272D01*
X133835Y-153814D01*
X135581Y-153231D01*
X137109Y-153522D01*
X138201Y-154106D01*
X139293Y-155272D01*
G01X149588Y-157022D02*
X156575D01*
X155920Y-154980D01*
X154828Y-153814D01*
X153300Y-153231D01*
X151771Y-153522D01*
X150461Y-154397D01*
X149588Y-156439D01*
X149151Y-158189D01*
Y-159939D01*
X149588Y-161689D01*
X150680Y-163439D01*
X151990Y-164605D01*
X153518Y-164897D01*
X155046Y-164314D01*
X156575Y-162564D01*
G01X170363Y-164897D02*
Y-147397D01*
G01X376163Y-209897D02*
Y-192397D01*
X373543Y-195897D01*
G01Y-209897D02*
X378783D01*
G01X396283D02*
Y-192397D01*
X388204Y-204939D01*
X399122D01*
G01X406360Y-207273D02*
X407669Y-208731D01*
X409198Y-209605D01*
X411163Y-209897D01*
X413128Y-209314D01*
X414656Y-208147D01*
X415748Y-206106D01*
X415966Y-203772D01*
X415530Y-201439D01*
X414438Y-199980D01*
X412909Y-198814D01*
X411381Y-198522D01*
X409853Y-198814D01*
X407888Y-199980D01*
X408543Y-192397D01*
X414438D01*
G01X431283Y-209897D02*
Y-192397D01*
X423204Y-204939D01*
X434122D01*
G01X441360Y-207273D02*
X442669Y-208731D01*
X444198Y-209605D01*
X446163Y-209897D01*
X448128Y-209314D01*
X449656Y-208147D01*
X450748Y-206106D01*
X450966Y-203772D01*
X450530Y-201439D01*
X449438Y-199980D01*
X447909Y-198814D01*
X446381Y-198522D01*
X444853Y-198814D01*
X442888Y-199980D01*
X443543Y-192397D01*
X449438D01*
G01X363046Y-164897D02*
Y-147397D01*
X368286D01*
X370033Y-148272D01*
X371343Y-150314D01*
X371780Y-152647D01*
X371343Y-154980D01*
X370251Y-156730D01*
X368286Y-157606D01*
X363046D01*
G01X389716Y-148856D02*
X388406Y-147980D01*
X386878Y-147397D01*
X385131D01*
X383166Y-148272D01*
X381638Y-149730D01*
X380546Y-151481D01*
X379673Y-154397D01*
X379454Y-157022D01*
X379891Y-159647D01*
X380546Y-161397D01*
X381856Y-163147D01*
X383385Y-164314D01*
X384913Y-164897D01*
X386441D01*
X387970Y-164314D01*
X389280Y-163439D01*
X390372Y-162273D01*
G01X404159Y-155564D02*
X405033Y-154689D01*
X405688Y-153231D01*
X406125Y-151188D01*
X405688Y-149439D01*
X404815Y-148272D01*
X403286Y-147397D01*
X397391D01*
Y-164897D01*
X404596D01*
X406125Y-163731D01*
X406998Y-161980D01*
X407435Y-159939D01*
X406998Y-157897D01*
X405688Y-156147D01*
X404159Y-155564D01*
X397391D01*
G01X413363Y-170730D02*
X426463D01*
G01X432391Y-164897D02*
Y-147397D01*
X442435Y-164897D01*
Y-147397D01*
G01X454913Y-164897D02*
X453166Y-164605D01*
X451638Y-163439D01*
X450328Y-161689D01*
X449454Y-159647D01*
X449018Y-157314D01*
Y-154980D01*
X449454Y-152647D01*
X450328Y-150605D01*
X451638Y-148856D01*
X453166Y-147689D01*
X454913Y-147397D01*
X456659Y-147689D01*
X458188Y-148856D01*
X459498Y-150605D01*
X460372Y-152647D01*
X460808Y-154980D01*
Y-157314D01*
X460372Y-159647D01*
X459498Y-161689D01*
X458188Y-163439D01*
X456659Y-164605D01*
X454913Y-164897D01*
G01X505754Y-147397D02*
X511213Y-164897D01*
X516672Y-147397D01*
G01X533080Y-164897D02*
X524346D01*
Y-147397D01*
X533080D01*
G01X529586Y-155855D02*
X524346D01*
G01X541846Y-164897D02*
Y-147397D01*
X547305D01*
X549051Y-148272D01*
X550143Y-149439D01*
X550580Y-151772D01*
X550143Y-154106D01*
X548833Y-155564D01*
X547305Y-156439D01*
X541846D01*
G01X547305D02*
X550580Y-164897D01*
G01X563713Y-165480D02*
X563276Y-165189D01*
Y-164605D01*
X563713Y-164314D01*
X564150Y-164605D01*
Y-165189D01*
X563713Y-165480D01*
G01X524128Y-207564D02*
X525875Y-209022D01*
X527840Y-209897D01*
X529586D01*
X531333Y-209022D01*
X532643Y-207564D01*
X533298Y-205522D01*
X532861Y-203481D01*
X531770Y-201730D01*
X529805Y-200564D01*
X527185Y-199980D01*
X525656Y-198814D01*
X525001Y-196772D01*
X525438Y-194730D01*
X526530Y-193272D01*
X528058Y-192397D01*
X529586D01*
X531115Y-192980D01*
X532425Y-194439D01*
G01X540754Y-209897D02*
X546213Y-192397D01*
X551672Y-209897D01*
G01X549706Y-203772D02*
X542719D01*
G01X652413Y-192397D02*
Y-209897D01*
G01X647391Y-192397D02*
X657435D01*
G01X665328Y-207564D02*
X667075Y-209022D01*
X669040Y-209897D01*
X670786D01*
X672533Y-209022D01*
X673843Y-207564D01*
X674498Y-205522D01*
X674061Y-203481D01*
X672970Y-201730D01*
X671005Y-200564D01*
X668385Y-199980D01*
X666856Y-198814D01*
X666201Y-196772D01*
X666638Y-194730D01*
X667730Y-193272D01*
X669258Y-192397D01*
X670786D01*
X672315Y-192980D01*
X673625Y-194439D01*
G01X681736Y-209897D02*
Y-192397D01*
X687413Y-206980D01*
X693090Y-192397D01*
Y-209897D01*
G01X700110D02*
Y-192397D01*
X704476D01*
X706223Y-193272D01*
X707533Y-194439D01*
X708625Y-196188D01*
X709498Y-198231D01*
X709716Y-201147D01*
X709498Y-204064D01*
X708625Y-206106D01*
X707533Y-207856D01*
X706223Y-209022D01*
X704476Y-209897D01*
X700110D01*
G01X630546Y-147397D02*
Y-164897D01*
X639280D01*
G01X656343D02*
Y-153231D01*
G01Y-155272D02*
X655470Y-154106D01*
X654159Y-153522D01*
X652631Y-153231D01*
X651103Y-153814D01*
X649793Y-154980D01*
X648919Y-156730D01*
X648483Y-159064D01*
X648919Y-161397D01*
X649793Y-163147D01*
X651103Y-164314D01*
X652631Y-164897D01*
X654159Y-164605D01*
X655470Y-163731D01*
X656343Y-162564D01*
G01X665328Y-170147D02*
X666638Y-170730D01*
X668385Y-170147D01*
X669476Y-168981D01*
X670350Y-167522D01*
X671659Y-162856D01*
X674498Y-153231D01*
G01X667511D02*
X671659Y-162856D01*
G01X684138Y-157022D02*
X691125D01*
X690470Y-154980D01*
X689378Y-153814D01*
X687850Y-153231D01*
X686321Y-153522D01*
X685011Y-154397D01*
X684138Y-156439D01*
X683701Y-158189D01*
Y-159939D01*
X684138Y-161689D01*
X685230Y-163439D01*
X686540Y-164605D01*
X688068Y-164897D01*
X689596Y-164314D01*
X691125Y-162564D01*
G01X701856Y-164897D02*
Y-153231D01*
G01Y-155564D02*
X702948Y-154397D01*
X704040Y-153522D01*
X705568Y-153231D01*
X706659Y-153522D01*
X707970Y-154397D01*
G01X719138Y-162856D02*
X720230Y-164022D01*
X721758Y-164897D01*
X723068D01*
X724378Y-164314D01*
X725251Y-163439D01*
X725688Y-162273D01*
X725470Y-160522D01*
X724596Y-159647D01*
X720666Y-157897D01*
X719793Y-155855D01*
X720230Y-154397D01*
X721103Y-153522D01*
X722413Y-153231D01*
X723723Y-153522D01*
X725033Y-154397D01*
G01X790596Y-209897D02*
Y-192397D01*
X796055D01*
X797801Y-193272D01*
X798893Y-194439D01*
X799330Y-196772D01*
X798893Y-199106D01*
X797583Y-200564D01*
X796055Y-201439D01*
X790596D01*
G01X796055D02*
X799330Y-209897D01*
G01X809188Y-202022D02*
X816175D01*
X815520Y-199980D01*
X814428Y-198814D01*
X812900Y-198231D01*
X811371Y-198522D01*
X810061Y-199397D01*
X809188Y-201439D01*
X808751Y-203189D01*
Y-204939D01*
X809188Y-206689D01*
X810280Y-208439D01*
X811590Y-209605D01*
X813118Y-209897D01*
X814646Y-209314D01*
X816175Y-207564D01*
G01X826033Y-209897D02*
Y-192397D01*
G01Y-201147D02*
X827125Y-199397D01*
X828435Y-198522D01*
X829745Y-198231D01*
X831709Y-198814D01*
X833020Y-199980D01*
X833893Y-202022D01*
Y-204355D01*
X833456Y-206689D01*
X832583Y-208439D01*
X831055Y-209605D01*
X829745Y-209897D01*
X828435Y-209605D01*
X827125Y-208731D01*
X826033Y-207273D01*
G01X844188Y-202022D02*
X851175D01*
X850520Y-199980D01*
X849428Y-198814D01*
X847900Y-198231D01*
X846371Y-198522D01*
X845061Y-199397D01*
X844188Y-201439D01*
X843751Y-203189D01*
Y-204939D01*
X844188Y-206689D01*
X845280Y-208439D01*
X846590Y-209605D01*
X848118Y-209897D01*
X849646Y-209314D01*
X851175Y-207564D01*
G01X868456Y-199689D02*
X866928Y-198522D01*
X865618Y-198231D01*
X863871Y-198814D01*
X862561Y-199980D01*
X861688Y-202022D01*
X861469Y-204064D01*
X861688Y-206106D01*
X862561Y-207856D01*
X863871Y-209314D01*
X865618Y-209897D01*
X867146Y-209314D01*
X868456Y-208147D01*
G01X885956Y-199689D02*
X884428Y-198522D01*
X883118Y-198231D01*
X881371Y-198814D01*
X880061Y-199980D01*
X879188Y-202022D01*
X878969Y-204064D01*
X879188Y-206106D01*
X880061Y-207856D01*
X881371Y-209314D01*
X883118Y-209897D01*
X884646Y-209314D01*
X885956Y-208147D01*
G01X903893Y-209897D02*
Y-198231D01*
G01Y-200272D02*
X903020Y-199106D01*
X901709Y-198522D01*
X900181Y-198231D01*
X898653Y-198814D01*
X897343Y-199980D01*
X896469Y-201730D01*
X896033Y-204064D01*
X896469Y-206397D01*
X897343Y-208147D01*
X898653Y-209314D01*
X900181Y-209897D01*
X901709Y-209605D01*
X903020Y-208731D01*
X903893Y-207564D01*
G01X781410Y-164897D02*
Y-147397D01*
X785776D01*
X787523Y-148272D01*
X788833Y-149439D01*
X789925Y-151188D01*
X790798Y-153231D01*
X791016Y-156147D01*
X790798Y-159064D01*
X789925Y-161106D01*
X788833Y-162856D01*
X787523Y-164022D01*
X785776Y-164897D01*
X781410D01*
G01X800438Y-157022D02*
X807425D01*
X806770Y-154980D01*
X805678Y-153814D01*
X804150Y-153231D01*
X802621Y-153522D01*
X801311Y-154397D01*
X800438Y-156439D01*
X800001Y-158189D01*
Y-159939D01*
X800438Y-161689D01*
X801530Y-163439D01*
X802840Y-164605D01*
X804368Y-164897D01*
X805896Y-164314D01*
X807425Y-162564D01*
G01X817938Y-162856D02*
X819030Y-164022D01*
X820558Y-164897D01*
X821868D01*
X823178Y-164314D01*
X824051Y-163439D01*
X824488Y-162273D01*
X824270Y-160522D01*
X823396Y-159647D01*
X819466Y-157897D01*
X818593Y-155855D01*
X819030Y-154397D01*
X819903Y-153522D01*
X821213Y-153231D01*
X822523Y-153522D01*
X823833Y-154397D01*
G01X838713Y-153231D02*
Y-164897D01*
G01Y-148564D02*
X838276Y-148272D01*
Y-147689D01*
X838713Y-147397D01*
X839150Y-147689D01*
Y-148272D01*
X838713Y-148564D01*
G01X853156Y-169272D02*
X854685Y-170439D01*
X856431Y-170730D01*
X857959Y-170439D01*
X859270Y-168981D01*
X860143Y-166939D01*
Y-153231D01*
G01Y-155564D02*
X859270Y-154397D01*
X857959Y-153522D01*
X856431Y-153231D01*
X854685Y-153814D01*
X853593Y-154980D01*
X852719Y-157022D01*
X852283Y-159064D01*
X852501Y-160814D01*
X853375Y-162856D01*
X854685Y-164314D01*
X856431Y-164897D01*
X857741Y-164605D01*
X859270Y-163439D01*
X860143Y-162273D01*
G01X870001Y-164897D02*
Y-153231D01*
G01Y-156147D02*
X870875Y-154689D01*
X872185Y-153522D01*
X873931Y-153231D01*
X875459Y-153522D01*
X876770Y-154689D01*
X877425Y-156730D01*
Y-164897D01*
G01X887938Y-157022D02*
X894925D01*
X894270Y-154980D01*
X893178Y-153814D01*
X891650Y-153231D01*
X890121Y-153522D01*
X888811Y-154397D01*
X887938Y-156439D01*
X887501Y-158189D01*
Y-159939D01*
X887938Y-161689D01*
X889030Y-163439D01*
X890340Y-164605D01*
X891868Y-164897D01*
X893396Y-164314D01*
X894925Y-162564D01*
G01X905656Y-164897D02*
Y-153231D01*
G01Y-155564D02*
X906748Y-154397D01*
X907840Y-153522D01*
X909368Y-153231D01*
X910459Y-153522D01*
X911770Y-154397D01*
G01X952413Y-192397D02*
X950666Y-192980D01*
X949356Y-194439D01*
X948483Y-196188D01*
X947828Y-198522D01*
X947610Y-201147D01*
X947828Y-203772D01*
X948483Y-206106D01*
X949356Y-207856D01*
X950666Y-209314D01*
X952413Y-209897D01*
X954159Y-209314D01*
X955470Y-207856D01*
X956343Y-206106D01*
X956998Y-203772D01*
X957216Y-201147D01*
X956998Y-198522D01*
X956343Y-196188D01*
X955470Y-194439D01*
X954159Y-192980D01*
X952413Y-192397D01*
G01X969913Y-209897D02*
X971441Y-209605D01*
X973188Y-208731D01*
X974280Y-207273D01*
X974716Y-205230D01*
X974280Y-203189D01*
X972970Y-201439D01*
X971005Y-200564D01*
X968821D01*
X967511Y-199980D01*
X966419Y-198522D01*
X965983Y-196481D01*
X966638Y-194439D01*
X968166Y-192980D01*
X969913Y-192397D01*
X971659Y-192980D01*
X973188Y-194439D01*
X973843Y-196481D01*
X973406Y-198522D01*
X972315Y-199980D01*
X971005Y-200564D01*
X968821D01*
X966856Y-201439D01*
X965546Y-203189D01*
X965110Y-205230D01*
X965546Y-207273D01*
X966638Y-208731D01*
X968385Y-209605D01*
X969913Y-209897D01*
G01X983483Y-210480D02*
X991343Y-192397D01*
G01X1004913D02*
X1003166Y-192980D01*
X1001856Y-194439D01*
X1000983Y-196188D01*
X1000328Y-198522D01*
X1000110Y-201147D01*
X1000328Y-203772D01*
X1000983Y-206106D01*
X1001856Y-207856D01*
X1003166Y-209314D01*
X1004913Y-209897D01*
X1006659Y-209314D01*
X1007970Y-207856D01*
X1008843Y-206106D01*
X1009498Y-203772D01*
X1009716Y-201147D01*
X1009498Y-198522D01*
X1008843Y-196188D01*
X1007970Y-194439D01*
X1006659Y-192980D01*
X1004913Y-192397D01*
G01X1022413Y-209897D02*
Y-192397D01*
X1019793Y-195897D01*
G01Y-209897D02*
X1025033D01*
G01X1035983Y-210480D02*
X1043843Y-192397D01*
G01X1053265Y-195314D02*
X1054575Y-193564D01*
X1056103Y-192689D01*
X1057850Y-192397D01*
X1060033Y-192980D01*
X1061561Y-194439D01*
X1061998Y-196188D01*
X1061780Y-197939D01*
X1060906Y-199397D01*
X1056540Y-202314D01*
X1054575Y-204355D01*
X1053265Y-207273D01*
X1052828Y-209897D01*
X1061998D01*
G01X1074913Y-192397D02*
X1073166Y-192980D01*
X1071856Y-194439D01*
X1070983Y-196188D01*
X1070328Y-198522D01*
X1070110Y-201147D01*
X1070328Y-203772D01*
X1070983Y-206106D01*
X1071856Y-207856D01*
X1073166Y-209314D01*
X1074913Y-209897D01*
X1076659Y-209314D01*
X1077970Y-207856D01*
X1078843Y-206106D01*
X1079498Y-203772D01*
X1079716Y-201147D01*
X1079498Y-198522D01*
X1078843Y-196188D01*
X1077970Y-194439D01*
X1076659Y-192980D01*
X1074913Y-192397D01*
G01X1092413Y-209897D02*
Y-192397D01*
X1089793Y-195897D01*
G01Y-209897D02*
X1095033D01*
G01X1112533D02*
Y-192397D01*
X1104454Y-204939D01*
X1115372D01*
G01X1000110Y-164897D02*
Y-147397D01*
X1004476D01*
X1006223Y-148272D01*
X1007533Y-149439D01*
X1008625Y-151188D01*
X1009498Y-153231D01*
X1009716Y-156147D01*
X1009498Y-159064D01*
X1008625Y-161106D01*
X1007533Y-162856D01*
X1006223Y-164022D01*
X1004476Y-164897D01*
X1000110D01*
G01X1026343D02*
Y-153231D01*
G01Y-155272D02*
X1025470Y-154106D01*
X1024159Y-153522D01*
X1022631Y-153231D01*
X1021103Y-153814D01*
X1019793Y-154980D01*
X1018919Y-156730D01*
X1018483Y-159064D01*
X1018919Y-161397D01*
X1019793Y-163147D01*
X1021103Y-164314D01*
X1022631Y-164897D01*
X1024159Y-164605D01*
X1025470Y-163731D01*
X1026343Y-162564D01*
G01X1039913Y-147397D02*
Y-164897D01*
G01X1036856Y-153231D02*
X1042970D01*
G01X1054138Y-157022D02*
X1061125D01*
X1060470Y-154980D01*
X1059378Y-153814D01*
X1057850Y-153231D01*
X1056321Y-153522D01*
X1055011Y-154397D01*
X1054138Y-156439D01*
X1053701Y-158189D01*
Y-159939D01*
X1054138Y-161689D01*
X1055230Y-163439D01*
X1056540Y-164605D01*
X1058068Y-164897D01*
X1059596Y-164314D01*
X1061125Y-162564D01*
G01X1041337Y24677D02*
Y0D01*
G01Y217343D02*
Y48297D01*
G01Y0D02*
X1097204D01*
G01X1033463Y48297D02*
G03X1041337I3937J0D01*
G01Y24677D02*
G03X1033463I-3937J0D01*
G01Y48297D02*
G03X1041337I3937J0D01*
G01Y24677D02*
G03X1033463I-3937J0D01*
G01X1041337Y217343D02*
G03X1033463I-3937J0D01*
G01X1041337D02*
G03X1033463I-3937J0D01*
G01X1041337Y445039D02*
Y240963D01*
G01X1033463D02*
G03X1041337I3937J0D01*
G01X1033463D02*
G03X1041337I3937J0D01*
G01Y697474D02*
Y468601D01*
G01X1033463Y468659D02*
G03X1041337I3937J0D01*
G01Y445039D02*
G03X1033463I-3937J0D01*
G01Y468659D02*
G03X1041337I3937J0D01*
G01Y445039D02*
G03X1033463I-3937J0D01*
G01X1041337Y996851D02*
Y721093D01*
G01X1033463D02*
G03X1041337I3937J0D01*
G01Y697474D02*
G03X1033463I-3937J-1D01*
G01Y721093D02*
G03X1041337I3937J0D01*
G01Y697474D02*
G03X1033463I-3937J-1D01*
G01X1041337Y1344059D02*
Y1020472D01*
G01X1033463D02*
G03X1041337I3937J0D01*
G01Y996851D02*
G03X1033463I-3937J1D01*
G01Y1020472D02*
G03X1041337I3937J0D01*
G01Y996851D02*
G03X1033463I-3937J1D01*
G01X1041337Y1367679D02*
Y1393701D01*
G01X1033463Y1367679D02*
G03X1041337I3937J0D01*
G01Y1344059D02*
G03X1033463I-3937J0D01*
G01Y1367679D02*
G03X1041337I3937J0D01*
G01Y1344059D02*
G03X1033463I-3937J0D01*
G01X1041337Y1393701D02*
X1097204D01*
G01X1041337Y1733129D02*
Y1716535D01*
G01X1065042D02*
X1041337D01*
G01X1056337D02*
X1097204D01*
G01X1041337Y1739719D02*
Y1731535D01*
G01Y1959242D02*
Y1763311D01*
G01X1033463Y1763339D02*
G03X1041337I3937J0D01*
G01Y1739719D02*
G03X1033463I-3937J0D01*
G01Y1763339D02*
G03X1041337I3937J0D01*
G01Y1739719D02*
G03X1033463I-3937J0D01*
G01X1041337Y1959242D02*
G03X1033463I-3937J0D01*
G01X1041337D02*
G03X1033463I-3937J0D01*
G01X1041337Y1992126D02*
X1097204D01*
G01X1041337Y1982862D02*
Y1992126D01*
G01X1033463Y1982862D02*
G03X1041337I3937J0D01*
G01X1033463D02*
G03X1041337I3937J0D01*
G01X1112204Y648419D02*
Y15000D01*
G01X1097204Y0D02*
G03X1112204Y15000I0J15000D01*
G01Y656293D02*
G03Y648419I0J-3937D01*
G01Y1378701D02*
Y656293D01*
G01Y1378701D02*
G03X1097204Y1393701I-15000J0D01*
G01Y1716535D02*
G03X1112204Y1731535I0J15000D01*
G01Y1977126D02*
Y1731535D01*
G01Y1977126D02*
G03X1097204Y1992126I-15000J0D01*
G54D69*
X241500Y1085625D03*
X234000Y1089500D03*
Y1081750D03*
M02*
